G04 ================== begin FILE IDENTIFICATION RECORD ==================*
G04 Layout Name:  D:/<user>/Wistron_project/16369-sd/gbr/16369-sd.brd*
G04 Film Name:    SE_REF_L1*
G04 File Format:  Gerber RS274X*
G04 File Origin:  Cadence Allegro 16.5-S056*
G04 Origin Date:  Wed Mar 29 13:12:57 2017*
G04 *
G04 Layer:  BOARD GEOMETRY/SE_REF_L1_TBL*
G04 Layer:  BOARD GEOMETRY/SE_REF_L1_TOP*
G04 Layer:  BOARD GEOMETRY/PANEL_OUTLINE*
G04 *
G04 Offset:    (0.00 0.00)*
G04 Mirror:    No*
G04 Mode:      Positive*
G04 Rotation:  0*
G04 FullContactRelief:  No*
G04 UndefLineWidth:     6.00*
G04 ================== end FILE IDENTIFICATION RECORD ====================*
%FSLAX35Y35*MOIN*%
%IR0*IPPOS*OFA0.00000B0.00000*MIA0B0*SFA1.00000B1.00000*%
%ADD10C,.02*%
%ADD11C,.006*%
%ADD12C,.00675*%
G75*
%LPD*%
G75*
G54D10*
G01X562899Y673913D02*
X1280399D01*
G01X562899Y639263D02*
X1280399D01*
G01X562899Y708563D02*
Y639263D01*
G01Y708563D02*
X1280399D01*
G01X737899D02*
Y639263D01*
G01X965399Y708563D02*
Y639263D01*
G01X1070399Y708563D02*
Y639263D01*
G01X1280399Y708563D02*
Y639263D01*
G54D11*
G01X-25246Y-59178D02*
Y-76678D01*
G01X-30268Y-59178D02*
X-20224D01*
G01X-11458Y-76678D02*
Y-59178D01*
G01Y-67636D02*
X-10366Y-66178D01*
X-9274Y-65303D01*
X-7528Y-65012D01*
X-6218Y-65303D01*
X-4689Y-66470D01*
X-4034Y-68220D01*
Y-76678D01*
G01X9754Y-65012D02*
Y-76678D01*
G01Y-60345D02*
X9317Y-60053D01*
Y-59470D01*
X9754Y-59178D01*
X10191Y-59470D01*
Y-60053D01*
X9754Y-60345D01*
G01X23979Y-74637D02*
X25071Y-75803D01*
X26599Y-76678D01*
X27909D01*
X29219Y-76095D01*
X30092Y-75220D01*
X30529Y-74054D01*
X30311Y-72303D01*
X29437Y-71428D01*
X25507Y-69678D01*
X24634Y-67636D01*
X25071Y-66178D01*
X25944Y-65303D01*
X27254Y-65012D01*
X28564Y-65303D01*
X29874Y-66178D01*
G01X59197Y-81053D02*
X60726Y-82220D01*
X62472Y-82511D01*
X64000Y-82220D01*
X65311Y-80762D01*
X66184Y-78720D01*
Y-65012D01*
G01Y-67345D02*
X65311Y-66178D01*
X64000Y-65303D01*
X62472Y-65012D01*
X60726Y-65595D01*
X59634Y-66761D01*
X58760Y-68803D01*
X58324Y-70845D01*
X58542Y-72595D01*
X59416Y-74637D01*
X60726Y-76095D01*
X62472Y-76678D01*
X63782Y-76386D01*
X65311Y-75220D01*
X66184Y-74054D01*
G01X76479Y-68803D02*
X83466D01*
X82811Y-66761D01*
X81719Y-65595D01*
X80191Y-65012D01*
X78662Y-65303D01*
X77352Y-66178D01*
X76479Y-68220D01*
X76042Y-69970D01*
Y-71720D01*
X76479Y-73470D01*
X77571Y-75220D01*
X78881Y-76386D01*
X80409Y-76678D01*
X81937Y-76095D01*
X83466Y-74345D01*
G01X94197Y-76678D02*
Y-65012D01*
G01Y-67345D02*
X95289Y-66178D01*
X96381Y-65303D01*
X97909Y-65012D01*
X99000Y-65303D01*
X100311Y-66178D01*
G01X110824Y-76678D02*
Y-59178D01*
G01Y-67928D02*
X111916Y-66178D01*
X113226Y-65303D01*
X114536Y-65012D01*
X116500Y-65595D01*
X117811Y-66761D01*
X118684Y-68803D01*
Y-71136D01*
X118247Y-73470D01*
X117374Y-75220D01*
X115846Y-76386D01*
X114536Y-76678D01*
X113226Y-76386D01*
X111916Y-75512D01*
X110824Y-74054D01*
G01X128979Y-68803D02*
X135966D01*
X135311Y-66761D01*
X134219Y-65595D01*
X132691Y-65012D01*
X131162Y-65303D01*
X129852Y-66178D01*
X128979Y-68220D01*
X128542Y-69970D01*
Y-71720D01*
X128979Y-73470D01*
X130071Y-75220D01*
X131381Y-76386D01*
X132909Y-76678D01*
X134437Y-76095D01*
X135966Y-74345D01*
G01X146697Y-76678D02*
Y-65012D01*
G01Y-67345D02*
X147789Y-66178D01*
X148881Y-65303D01*
X150409Y-65012D01*
X151500Y-65303D01*
X152811Y-66178D01*
G01X184754Y-65012D02*
Y-76678D01*
G01Y-60345D02*
X184317Y-60053D01*
Y-59470D01*
X184754Y-59178D01*
X185191Y-59470D01*
Y-60053D01*
X184754Y-60345D01*
G01X198979Y-74637D02*
X200071Y-75803D01*
X201599Y-76678D01*
X202909D01*
X204219Y-76095D01*
X205092Y-75220D01*
X205529Y-74054D01*
X205311Y-72303D01*
X204437Y-71428D01*
X200507Y-69678D01*
X199634Y-67636D01*
X200071Y-66178D01*
X200944Y-65303D01*
X202254Y-65012D01*
X203564Y-65303D01*
X204874Y-66178D01*
G01X233760Y-81053D02*
X235289Y-82220D01*
X236599Y-82511D01*
X238346Y-81928D01*
X239656Y-80470D01*
X240311Y-77844D01*
Y-65012D01*
G01Y-60345D02*
X239874Y-60053D01*
Y-59470D01*
X240311Y-59178D01*
X240747Y-59470D01*
Y-60053D01*
X240311Y-60345D01*
G01X251042Y-65012D02*
Y-73178D01*
X251916Y-75220D01*
X253226Y-76386D01*
X254754Y-76678D01*
X256282Y-76386D01*
X257592Y-75220D01*
X258466Y-73178D01*
G01Y-76678D02*
Y-65012D01*
G01X268979Y-74637D02*
X270071Y-75803D01*
X271599Y-76678D01*
X272909D01*
X274219Y-76095D01*
X275092Y-75220D01*
X275529Y-74054D01*
X275311Y-72303D01*
X274437Y-71428D01*
X270507Y-69678D01*
X269634Y-67636D01*
X270071Y-66178D01*
X270944Y-65303D01*
X272254Y-65012D01*
X273564Y-65303D01*
X274874Y-66178D01*
G01X289754Y-59178D02*
Y-76678D01*
G01X286697Y-65012D02*
X292811D01*
G01X323444Y-76678D02*
Y-61803D01*
X323881Y-60345D01*
X324754Y-59470D01*
X326064Y-59178D01*
X327374Y-59761D01*
X328029Y-61220D01*
G01X325409Y-66178D02*
X321042D01*
G01X342254Y-76678D02*
X340944Y-76386D01*
X339634Y-75220D01*
X338760Y-73178D01*
X338324Y-70845D01*
X338760Y-68511D01*
X339634Y-66470D01*
X340944Y-65303D01*
X342254Y-65012D01*
X343564Y-65303D01*
X344874Y-66470D01*
X345747Y-68511D01*
X345966Y-70845D01*
X345747Y-73178D01*
X344874Y-75220D01*
X343564Y-76386D01*
X342254Y-76678D01*
G01X356697D02*
Y-65012D01*
G01Y-67345D02*
X357789Y-66178D01*
X358881Y-65303D01*
X360409Y-65012D01*
X361500Y-65303D01*
X362811Y-66178D01*
G01X390169Y-81928D02*
X391479Y-82511D01*
X393226Y-81928D01*
X394317Y-80762D01*
X395191Y-79303D01*
X396500Y-74637D01*
X399339Y-65012D01*
G01X392352D02*
X396500Y-74637D01*
G01X412254Y-76678D02*
X410944Y-76386D01*
X409634Y-75220D01*
X408760Y-73178D01*
X408324Y-70845D01*
X408760Y-68511D01*
X409634Y-66470D01*
X410944Y-65303D01*
X412254Y-65012D01*
X413564Y-65303D01*
X414874Y-66470D01*
X415747Y-68511D01*
X415966Y-70845D01*
X415747Y-73178D01*
X414874Y-75220D01*
X413564Y-76386D01*
X412254Y-76678D01*
G01X426042Y-65012D02*
Y-73178D01*
X426916Y-75220D01*
X428226Y-76386D01*
X429754Y-76678D01*
X431282Y-76386D01*
X432592Y-75220D01*
X433466Y-73178D01*
G01Y-76678D02*
Y-65012D01*
G01X444197Y-76678D02*
Y-65012D01*
G01Y-67345D02*
X445289Y-66178D01*
X446381Y-65303D01*
X447909Y-65012D01*
X449000Y-65303D01*
X450311Y-66178D01*
G01X479197Y-76678D02*
Y-65012D01*
G01Y-67345D02*
X480289Y-66178D01*
X481381Y-65303D01*
X482909Y-65012D01*
X484000Y-65303D01*
X485311Y-66178D01*
G01X496479Y-68803D02*
X503466D01*
X502811Y-66761D01*
X501719Y-65595D01*
X500191Y-65012D01*
X498662Y-65303D01*
X497352Y-66178D01*
X496479Y-68220D01*
X496042Y-69970D01*
Y-71720D01*
X496479Y-73470D01*
X497571Y-75220D01*
X498881Y-76386D01*
X500409Y-76678D01*
X501937Y-76095D01*
X503466Y-74345D01*
G01X515944Y-76678D02*
Y-61803D01*
X516381Y-60345D01*
X517254Y-59470D01*
X518564Y-59178D01*
X519874Y-59761D01*
X520529Y-61220D01*
G01X517909Y-66178D02*
X513542D01*
G01X531479Y-68803D02*
X538466D01*
X537811Y-66761D01*
X536719Y-65595D01*
X535191Y-65012D01*
X533662Y-65303D01*
X532352Y-66178D01*
X531479Y-68220D01*
X531042Y-69970D01*
Y-71720D01*
X531479Y-73470D01*
X532571Y-75220D01*
X533881Y-76386D01*
X535409Y-76678D01*
X536937Y-76095D01*
X538466Y-74345D01*
G01X549197Y-76678D02*
Y-65012D01*
G01Y-67345D02*
X550289Y-66178D01*
X551381Y-65303D01*
X552909Y-65012D01*
X554000Y-65303D01*
X555311Y-66178D01*
G01X566479Y-68803D02*
X573466D01*
X572811Y-66761D01*
X571719Y-65595D01*
X570191Y-65012D01*
X568662Y-65303D01*
X567352Y-66178D01*
X566479Y-68220D01*
X566042Y-69970D01*
Y-71720D01*
X566479Y-73470D01*
X567571Y-75220D01*
X568881Y-76386D01*
X570409Y-76678D01*
X571937Y-76095D01*
X573466Y-74345D01*
G01X583542Y-76678D02*
Y-65012D01*
G01Y-67928D02*
X584416Y-66470D01*
X585726Y-65303D01*
X587472Y-65012D01*
X589000Y-65303D01*
X590311Y-66470D01*
X590966Y-68511D01*
Y-76678D01*
G01X608247Y-66470D02*
X606719Y-65303D01*
X605409Y-65012D01*
X603662Y-65595D01*
X602352Y-66761D01*
X601479Y-68803D01*
X601260Y-70845D01*
X601479Y-72887D01*
X602352Y-74637D01*
X603662Y-76095D01*
X605409Y-76678D01*
X606937Y-76095D01*
X608247Y-74928D01*
G01X618979Y-68803D02*
X625966D01*
X625311Y-66761D01*
X624219Y-65595D01*
X622691Y-65012D01*
X621162Y-65303D01*
X619852Y-66178D01*
X618979Y-68220D01*
X618542Y-69970D01*
Y-71720D01*
X618979Y-73470D01*
X620071Y-75220D01*
X621381Y-76386D01*
X622909Y-76678D01*
X624437Y-76095D01*
X625966Y-74345D01*
G01X657254Y-59178D02*
Y-76678D01*
G01X654197Y-65012D02*
X660311D01*
G01X674754Y-76678D02*
X673444Y-76386D01*
X672134Y-75220D01*
X671260Y-73178D01*
X670824Y-70845D01*
X671260Y-68511D01*
X672134Y-66470D01*
X673444Y-65303D01*
X674754Y-65012D01*
X676064Y-65303D01*
X677374Y-66470D01*
X678247Y-68511D01*
X678466Y-70845D01*
X678247Y-73178D01*
X677374Y-75220D01*
X676064Y-76386D01*
X674754Y-76678D01*
G01X708444D02*
Y-61803D01*
X708881Y-60345D01*
X709754Y-59470D01*
X711064Y-59178D01*
X712374Y-59761D01*
X713029Y-61220D01*
G01X710409Y-66178D02*
X706042D01*
G01X727254Y-65012D02*
Y-76678D01*
G01Y-60345D02*
X726817Y-60053D01*
Y-59470D01*
X727254Y-59178D01*
X727691Y-59470D01*
Y-60053D01*
X727254Y-60345D01*
G01X741042Y-76678D02*
Y-65012D01*
G01Y-67928D02*
X741916Y-66470D01*
X743226Y-65303D01*
X744972Y-65012D01*
X746500Y-65303D01*
X747811Y-66470D01*
X748466Y-68511D01*
Y-76678D01*
G01X766184Y-59178D02*
Y-76678D01*
G01Y-74054D02*
X765311Y-75512D01*
X764000Y-76386D01*
X762472Y-76678D01*
X760726Y-76095D01*
X759416Y-74637D01*
X758542Y-72887D01*
X758324Y-70845D01*
X758542Y-68803D01*
X759416Y-67053D01*
X760726Y-65595D01*
X762472Y-65012D01*
X764000Y-65303D01*
X765092Y-65887D01*
X766184Y-67053D01*
G01X797254Y-59178D02*
Y-76678D01*
G01X794197Y-65012D02*
X800311D01*
G01X811042Y-76678D02*
Y-59178D01*
G01Y-67636D02*
X812134Y-66178D01*
X813226Y-65303D01*
X814972Y-65012D01*
X816282Y-65303D01*
X817811Y-66470D01*
X818466Y-68220D01*
Y-76678D01*
G01X828979Y-68803D02*
X835966D01*
X835311Y-66761D01*
X834219Y-65595D01*
X832691Y-65012D01*
X831162Y-65303D01*
X829852Y-66178D01*
X828979Y-68220D01*
X828542Y-69970D01*
Y-71720D01*
X828979Y-73470D01*
X830071Y-75220D01*
X831381Y-76386D01*
X832909Y-76678D01*
X834437Y-76095D01*
X835966Y-74345D01*
G01X862669D02*
X864416Y-75803D01*
X866381Y-76678D01*
X868127D01*
X869874Y-75803D01*
X871184Y-74345D01*
X871839Y-72303D01*
X871402Y-70262D01*
X870311Y-68511D01*
X868346Y-67345D01*
X865726Y-66761D01*
X864197Y-65595D01*
X863542Y-63553D01*
X863979Y-61511D01*
X865071Y-60053D01*
X866599Y-59178D01*
X868127D01*
X869656Y-59761D01*
X870966Y-61220D01*
G01X889121Y-76678D02*
X880387D01*
Y-59178D01*
X889121D01*
G01X885627Y-67636D02*
X880387D01*
G01X919754Y-65012D02*
Y-76678D01*
G01Y-60345D02*
X919317Y-60053D01*
Y-59470D01*
X919754Y-59178D01*
X920191Y-59470D01*
Y-60053D01*
X919754Y-60345D01*
G01X930704Y-76678D02*
Y-65012D01*
G01Y-68220D02*
X931359Y-66761D01*
X932451Y-65595D01*
X933979Y-65012D01*
X935507Y-65595D01*
X936599Y-66761D01*
X937254Y-68220D01*
Y-76678D01*
G01Y-68220D02*
X937909Y-66761D01*
X939000Y-65595D01*
X940529Y-65012D01*
X942057Y-65595D01*
X943149Y-66761D01*
X943804Y-68511D01*
Y-76678D01*
G01X950824Y-82511D02*
Y-65012D01*
G01Y-67636D02*
X951916Y-66178D01*
X953007Y-65303D01*
X954754Y-65012D01*
X956282Y-65303D01*
X957811Y-66761D01*
X958466Y-68803D01*
X958684Y-70845D01*
X958466Y-72887D01*
X957811Y-74928D01*
X956500Y-76095D01*
X954754Y-76678D01*
X953226Y-76386D01*
X951697Y-75512D01*
X950824Y-74345D01*
G01X968979Y-68803D02*
X975966D01*
X975311Y-66761D01*
X974219Y-65595D01*
X972691Y-65012D01*
X971162Y-65303D01*
X969852Y-66178D01*
X968979Y-68220D01*
X968542Y-69970D01*
Y-71720D01*
X968979Y-73470D01*
X970071Y-75220D01*
X971381Y-76386D01*
X972909Y-76678D01*
X974437Y-76095D01*
X975966Y-74345D01*
G01X993684Y-59178D02*
Y-76678D01*
G01Y-74054D02*
X992811Y-75512D01*
X991500Y-76386D01*
X989972Y-76678D01*
X988226Y-76095D01*
X986916Y-74637D01*
X986042Y-72887D01*
X985824Y-70845D01*
X986042Y-68803D01*
X986916Y-67053D01*
X988226Y-65595D01*
X989972Y-65012D01*
X991500Y-65303D01*
X992592Y-65887D01*
X993684Y-67053D01*
G01X1011184Y-76678D02*
Y-65012D01*
G01Y-67053D02*
X1010311Y-65887D01*
X1009000Y-65303D01*
X1007472Y-65012D01*
X1005944Y-65595D01*
X1004634Y-66761D01*
X1003760Y-68511D01*
X1003324Y-70845D01*
X1003760Y-73178D01*
X1004634Y-74928D01*
X1005944Y-76095D01*
X1007472Y-76678D01*
X1009000Y-76386D01*
X1010311Y-75512D01*
X1011184Y-74345D01*
G01X1021042Y-76678D02*
Y-65012D01*
G01Y-67928D02*
X1021916Y-66470D01*
X1023226Y-65303D01*
X1024972Y-65012D01*
X1026500Y-65303D01*
X1027811Y-66470D01*
X1028466Y-68511D01*
Y-76678D01*
G01X1045747Y-66470D02*
X1044219Y-65303D01*
X1042909Y-65012D01*
X1041162Y-65595D01*
X1039852Y-66761D01*
X1038979Y-68803D01*
X1038760Y-70845D01*
X1038979Y-72887D01*
X1039852Y-74637D01*
X1041162Y-76095D01*
X1042909Y-76678D01*
X1044437Y-76095D01*
X1045747Y-74928D01*
G01X1056479Y-68803D02*
X1063466D01*
X1062811Y-66761D01*
X1061719Y-65595D01*
X1060191Y-65012D01*
X1058662Y-65303D01*
X1057352Y-66178D01*
X1056479Y-68220D01*
X1056042Y-69970D01*
Y-71720D01*
X1056479Y-73470D01*
X1057571Y-75220D01*
X1058881Y-76386D01*
X1060409Y-76678D01*
X1061937Y-76095D01*
X1063466Y-74345D01*
G01X1094754Y-59178D02*
Y-76678D01*
G01X1091697Y-65012D02*
X1097811D01*
G01X1109197Y-76678D02*
Y-65012D01*
G01Y-67345D02*
X1110289Y-66178D01*
X1111381Y-65303D01*
X1112909Y-65012D01*
X1114000Y-65303D01*
X1115311Y-66178D01*
G01X1133684Y-76678D02*
Y-65012D01*
G01Y-67053D02*
X1132811Y-65887D01*
X1131500Y-65303D01*
X1129972Y-65012D01*
X1128444Y-65595D01*
X1127134Y-66761D01*
X1126260Y-68511D01*
X1125824Y-70845D01*
X1126260Y-73178D01*
X1127134Y-74928D01*
X1128444Y-76095D01*
X1129972Y-76678D01*
X1131500Y-76386D01*
X1132811Y-75512D01*
X1133684Y-74345D01*
G01X1150747Y-66470D02*
X1149219Y-65303D01*
X1147909Y-65012D01*
X1146162Y-65595D01*
X1144852Y-66761D01*
X1143979Y-68803D01*
X1143760Y-70845D01*
X1143979Y-72887D01*
X1144852Y-74637D01*
X1146162Y-76095D01*
X1147909Y-76678D01*
X1149437Y-76095D01*
X1150747Y-74928D01*
G01X1161479Y-68803D02*
X1168466D01*
X1167811Y-66761D01*
X1166719Y-65595D01*
X1165191Y-65012D01*
X1163662Y-65303D01*
X1162352Y-66178D01*
X1161479Y-68220D01*
X1161042Y-69970D01*
Y-71720D01*
X1161479Y-73470D01*
X1162571Y-75220D01*
X1163881Y-76386D01*
X1165409Y-76678D01*
X1166937Y-76095D01*
X1168466Y-74345D01*
G01X1178979Y-74637D02*
X1180071Y-75803D01*
X1181599Y-76678D01*
X1182909D01*
X1184219Y-76095D01*
X1185092Y-75220D01*
X1185529Y-74054D01*
X1185311Y-72303D01*
X1184437Y-71428D01*
X1180507Y-69678D01*
X1179634Y-67636D01*
X1180071Y-66178D01*
X1180944Y-65303D01*
X1182254Y-65012D01*
X1183564Y-65303D01*
X1184874Y-66178D01*
G01X1217254Y-65012D02*
Y-76678D01*
G01Y-60345D02*
X1216817Y-60053D01*
Y-59470D01*
X1217254Y-59178D01*
X1217691Y-59470D01*
Y-60053D01*
X1217254Y-60345D01*
G01X1231042Y-76678D02*
Y-65012D01*
G01Y-67928D02*
X1231916Y-66470D01*
X1233226Y-65303D01*
X1234972Y-65012D01*
X1236500Y-65303D01*
X1237811Y-66470D01*
X1238466Y-68511D01*
Y-76678D01*
G01X1269754D02*
Y-59178D01*
G01X1291184Y-76678D02*
Y-65012D01*
G01Y-67053D02*
X1290311Y-65887D01*
X1289000Y-65303D01*
X1287472Y-65012D01*
X1285944Y-65595D01*
X1284634Y-66761D01*
X1283760Y-68511D01*
X1283324Y-70845D01*
X1283760Y-73178D01*
X1284634Y-74928D01*
X1285944Y-76095D01*
X1287472Y-76678D01*
X1289000Y-76386D01*
X1290311Y-75512D01*
X1291184Y-74345D01*
G01X1300169Y-81928D02*
X1301479Y-82511D01*
X1303226Y-81928D01*
X1304317Y-80762D01*
X1305191Y-79303D01*
X1306500Y-74637D01*
X1309339Y-65012D01*
G01X1302352D02*
X1306500Y-74637D01*
G01X1318979Y-68803D02*
X1325966D01*
X1325311Y-66761D01*
X1324219Y-65595D01*
X1322691Y-65012D01*
X1321162Y-65303D01*
X1319852Y-66178D01*
X1318979Y-68220D01*
X1318542Y-69970D01*
Y-71720D01*
X1318979Y-73470D01*
X1320071Y-75220D01*
X1321381Y-76386D01*
X1322909Y-76678D01*
X1324437Y-76095D01*
X1325966Y-74345D01*
G01X1336697Y-76678D02*
Y-65012D01*
G01Y-67345D02*
X1337789Y-66178D01*
X1338881Y-65303D01*
X1340409Y-65012D01*
X1341500Y-65303D01*
X1342811Y-66178D01*
G01X1370387Y-59178D02*
Y-76678D01*
X1379121D01*
G01X1392254D02*
Y-59178D01*
X1389634Y-62678D01*
G01Y-76678D02*
X1394874D01*
G01X1409754Y-77261D02*
X1409317Y-76970D01*
Y-76386D01*
X1409754Y-76095D01*
X1410191Y-76386D01*
Y-76970D01*
X1409754Y-77261D01*
G01X564864Y720646D02*
X566611Y719188D01*
X568576Y718313D01*
X570322D01*
X572069Y719188D01*
X573379Y720646D01*
X574034Y722688D01*
X573597Y724729D01*
X572506Y726480D01*
X570541Y727646D01*
X567921Y728230D01*
X566392Y729396D01*
X565737Y731438D01*
X566174Y733480D01*
X567266Y734938D01*
X568794Y735813D01*
X570322D01*
X571851Y735230D01*
X573161Y733771D01*
G01X591316Y718313D02*
X582582D01*
Y735813D01*
X591316D01*
G01X587822Y727355D02*
X582582D01*
G01X619329Y735813D02*
X624569D01*
G01X621949D02*
Y718313D01*
G01X619329D02*
X624569D01*
G01X633772D02*
Y735813D01*
X639449Y721230D01*
X645126Y735813D01*
Y718313D01*
G01X652582D02*
Y735813D01*
X657822D01*
X659569Y734938D01*
X660879Y732896D01*
X661316Y730563D01*
X660879Y728230D01*
X659787Y726480D01*
X657822Y725604D01*
X652582D01*
G01X678816Y718313D02*
X670082D01*
Y735813D01*
X678816D01*
G01X675322Y727355D02*
X670082D01*
G01X687146Y718313D02*
Y735813D01*
X691512D01*
X693259Y734938D01*
X694569Y733771D01*
X695661Y732022D01*
X696534Y729979D01*
X696752Y727063D01*
X696534Y724146D01*
X695661Y722104D01*
X694569Y720354D01*
X693259Y719188D01*
X691512Y718313D01*
X687146D01*
G01X703990D02*
X709449Y735813D01*
X714908Y718313D01*
G01X712942Y724438D02*
X705955D01*
G01X721927Y718313D02*
Y735813D01*
X731971Y718313D01*
Y735813D01*
G01X749252Y734354D02*
X747942Y735230D01*
X746414Y735813D01*
X744667D01*
X742702Y734938D01*
X741174Y733480D01*
X740082Y731729D01*
X739209Y728813D01*
X738990Y726188D01*
X739427Y723563D01*
X740082Y721813D01*
X741392Y720063D01*
X742921Y718896D01*
X744449Y718313D01*
X745977D01*
X747506Y718896D01*
X748816Y719771D01*
X749908Y720937D01*
G01X766316Y718313D02*
X757582D01*
Y735813D01*
X766316D01*
G01X762822Y727355D02*
X757582D01*
G01X796949Y735813D02*
Y718313D01*
G01X791927Y735813D02*
X801971D01*
G01X808990Y718313D02*
X814449Y735813D01*
X819908Y718313D01*
G01X817942Y724438D02*
X810955D01*
G01X833695Y727646D02*
X834569Y728521D01*
X835224Y729979D01*
X835661Y732022D01*
X835224Y733771D01*
X834351Y734938D01*
X832822Y735813D01*
X826927D01*
Y718313D01*
X834132D01*
X835661Y719479D01*
X836534Y721230D01*
X836971Y723271D01*
X836534Y725313D01*
X835224Y727063D01*
X833695Y727646D01*
X826927D01*
G01X845082Y735813D02*
Y718313D01*
X853816D01*
G01X871316D02*
X862582D01*
Y735813D01*
X871316D01*
G01X867822Y727355D02*
X862582D01*
G01X884449Y717730D02*
X884012Y718021D01*
Y718605D01*
X884449Y718896D01*
X884886Y718605D01*
Y718021D01*
X884449Y717730D01*
G01Y725604D02*
X884012Y725896D01*
Y726480D01*
X884449Y726771D01*
X884886Y726480D01*
Y725896D01*
X884449Y725604D01*
G01X915082Y735813D02*
Y718313D01*
X923816D01*
G01X936949D02*
Y735813D01*
X934329Y732313D01*
G01Y718313D02*
X939569D01*
G01X586529Y701163D02*
X591769D01*
G01X589149D02*
Y683663D01*
G01X586529D02*
X591769D01*
G01X600972D02*
Y701163D01*
X606649Y686580D01*
X612326Y701163D01*
Y683663D01*
G01X619782D02*
Y701163D01*
X625022D01*
X626769Y700288D01*
X628079Y698246D01*
X628516Y695913D01*
X628079Y693580D01*
X626987Y691830D01*
X625022Y690954D01*
X619782D01*
G01X640557Y677830D02*
X638374Y680746D01*
X637282Y683663D01*
Y695329D01*
X638374Y698246D01*
X640557Y701163D01*
G01X659149Y683663D02*
X657402Y683955D01*
X655874Y685121D01*
X654564Y686871D01*
X653690Y688913D01*
X653254Y691246D01*
Y693580D01*
X653690Y695913D01*
X654564Y697955D01*
X655874Y699704D01*
X657402Y700871D01*
X659149Y701163D01*
X660895Y700871D01*
X662424Y699704D01*
X663734Y697955D01*
X664608Y695913D01*
X665044Y693580D01*
Y691246D01*
X664608Y688913D01*
X663734Y686871D01*
X662424Y685121D01*
X660895Y683955D01*
X659149Y683663D01*
G01X672937D02*
Y701163D01*
G01Y692705D02*
X674029Y694163D01*
X675121Y695038D01*
X676867Y695329D01*
X678177Y695038D01*
X679706Y693871D01*
X680361Y692121D01*
Y683663D01*
G01X687599D02*
Y695329D01*
G01Y692121D02*
X688254Y693580D01*
X689346Y694746D01*
X690874Y695329D01*
X692402Y694746D01*
X693494Y693580D01*
X694149Y692121D01*
Y683663D01*
G01Y692121D02*
X694804Y693580D01*
X695895Y694746D01*
X697424Y695329D01*
X698952Y694746D01*
X700044Y693580D01*
X700699Y691830D01*
Y683663D01*
G01X712741Y677830D02*
X714924Y680746D01*
X716016Y683663D01*
Y695329D01*
X714924Y698246D01*
X712741Y701163D01*
G01X619346Y651637D02*
X620655Y650179D01*
X622184Y649305D01*
X624149Y649013D01*
X626114Y649596D01*
X627642Y650763D01*
X628734Y652804D01*
X628952Y655138D01*
X628516Y657471D01*
X627424Y658930D01*
X625895Y660096D01*
X624367Y660388D01*
X622839Y660096D01*
X620874Y658930D01*
X621529Y666513D01*
X627424D01*
G01X641649D02*
X639902Y665930D01*
X638592Y664471D01*
X637719Y662722D01*
X637064Y660388D01*
X636846Y657763D01*
X637064Y655138D01*
X637719Y652804D01*
X638592Y651054D01*
X639902Y649596D01*
X641649Y649013D01*
X643395Y649596D01*
X644706Y651054D01*
X645579Y652804D01*
X646234Y655138D01*
X646452Y657763D01*
X646234Y660388D01*
X645579Y662722D01*
X644706Y664471D01*
X643395Y665930D01*
X641649Y666513D01*
G01X659149Y648430D02*
X658712Y648721D01*
Y649305D01*
X659149Y649596D01*
X659586Y649305D01*
Y648721D01*
X659149Y648430D01*
G01X676649Y666513D02*
X674902Y665930D01*
X673592Y664471D01*
X672719Y662722D01*
X672064Y660388D01*
X671846Y657763D01*
X672064Y655138D01*
X672719Y652804D01*
X673592Y651054D01*
X674902Y649596D01*
X676649Y649013D01*
X678395Y649596D01*
X679706Y651054D01*
X680579Y652804D01*
X681234Y655138D01*
X681452Y657763D01*
X681234Y660388D01*
X680579Y662722D01*
X679706Y664471D01*
X678395Y665930D01*
X676649Y666513D01*
G01X821251Y656304D02*
X822779Y658346D01*
X824089Y659513D01*
X825836Y660096D01*
X827364Y659513D01*
X828456Y658346D01*
X829329Y656596D01*
X829547Y654555D01*
X829329Y652804D01*
X828456Y651054D01*
X827145Y649596D01*
X825617Y649013D01*
X823871Y649596D01*
X822342Y651346D01*
X821469Y653971D01*
X821251Y656888D01*
X821687Y660679D01*
X822342Y662722D01*
X823434Y664763D01*
X824962Y666221D01*
X826491Y666513D01*
X828019Y665930D01*
X829111Y664471D01*
G01X842899Y648430D02*
X842462Y648721D01*
Y649305D01*
X842899Y649596D01*
X843336Y649305D01*
Y648721D01*
X842899Y648430D01*
G01X859962Y649013D02*
X860399Y652804D01*
X861054Y656013D01*
X861927Y658930D01*
X863019Y662138D01*
X864766Y666513D01*
X856032D01*
G01X873096Y651637D02*
X874405Y650179D01*
X875934Y649305D01*
X877899Y649013D01*
X879864Y649596D01*
X881392Y650763D01*
X882484Y652804D01*
X882702Y655138D01*
X882266Y657471D01*
X881174Y658930D01*
X879645Y660096D01*
X878117Y660388D01*
X876589Y660096D01*
X874624Y658930D01*
X875279Y666513D01*
X881174D01*
G01X757599Y701163D02*
X760655Y683663D01*
X764149Y701163D01*
X767642Y683663D01*
X770699Y701163D01*
G01X779029D02*
X784269D01*
G01X781649D02*
Y683663D01*
G01X779029D02*
X784269D01*
G01X794346D02*
Y701163D01*
X798712D01*
X800459Y700288D01*
X801769Y699121D01*
X802861Y697372D01*
X803734Y695329D01*
X803952Y692413D01*
X803734Y689496D01*
X802861Y687454D01*
X801769Y685704D01*
X800459Y684538D01*
X798712Y683663D01*
X794346D01*
G01X816649Y701163D02*
Y683663D01*
G01X811627Y701163D02*
X821671D01*
G01X829564Y683663D02*
Y701163D01*
G01X838734D02*
Y683663D01*
G01Y692413D02*
X829564D01*
G01X850557Y677830D02*
X848374Y680746D01*
X847282Y683663D01*
Y695329D01*
X848374Y698246D01*
X850557Y701163D01*
G01X862599Y683663D02*
Y695329D01*
G01Y692121D02*
X863254Y693580D01*
X864346Y694746D01*
X865874Y695329D01*
X867402Y694746D01*
X868494Y693580D01*
X869149Y692121D01*
Y683663D01*
G01Y692121D02*
X869804Y693580D01*
X870895Y694746D01*
X872424Y695329D01*
X873952Y694746D01*
X875044Y693580D01*
X875699Y691830D01*
Y683663D01*
G01X886649Y695329D02*
Y683663D01*
G01Y699996D02*
X886212Y700288D01*
Y700871D01*
X886649Y701163D01*
X887086Y700871D01*
Y700288D01*
X886649Y699996D01*
G01X904149Y683663D02*
Y701163D01*
G01X918374Y685704D02*
X919466Y684538D01*
X920994Y683663D01*
X922304D01*
X923614Y684246D01*
X924487Y685121D01*
X924924Y686287D01*
X924706Y688038D01*
X923832Y688913D01*
X919902Y690663D01*
X919029Y692705D01*
X919466Y694163D01*
X920339Y695038D01*
X921649Y695329D01*
X922959Y695038D01*
X924269Y694163D01*
G01X940241Y677830D02*
X942424Y680746D01*
X943516Y683663D01*
Y695329D01*
X942424Y698246D01*
X940241Y701163D01*
G01X1004564Y651346D02*
X1006311Y649888D01*
X1008276Y649013D01*
X1010022D01*
X1011769Y649888D01*
X1013079Y651346D01*
X1013734Y653388D01*
X1013297Y655429D01*
X1012206Y657180D01*
X1010241Y658346D01*
X1007621Y658930D01*
X1006092Y660096D01*
X1005437Y662138D01*
X1005874Y664180D01*
X1006966Y665638D01*
X1008494Y666513D01*
X1010022D01*
X1011551Y665930D01*
X1012861Y664471D01*
G01X1031016Y649013D02*
X1022282D01*
Y666513D01*
X1031016D01*
G01X1027522Y658055D02*
X1022282D01*
G01X991649Y701163D02*
Y683663D01*
G01X986627Y701163D02*
X996671D01*
G01X1009149Y683663D02*
Y691538D01*
X1004782Y701163D01*
G01X1013516D02*
X1009149Y691538D01*
G01X1022282Y683663D02*
Y701163D01*
X1027522D01*
X1029269Y700288D01*
X1030579Y698246D01*
X1031016Y695913D01*
X1030579Y693580D01*
X1029487Y691830D01*
X1027522Y690954D01*
X1022282D01*
G01X1048516Y683663D02*
X1039782D01*
Y701163D01*
X1048516D01*
G01X1045022Y692705D02*
X1039782D01*
G01X1092282Y683663D02*
Y701163D01*
X1097741D01*
X1099487Y700288D01*
X1100579Y699121D01*
X1101016Y696788D01*
X1100579Y694454D01*
X1099269Y692996D01*
X1097741Y692121D01*
X1092282D01*
G01X1097741D02*
X1101016Y683663D01*
G01X1110874Y691538D02*
X1117861D01*
X1117206Y693580D01*
X1116114Y694746D01*
X1114586Y695329D01*
X1113057Y695038D01*
X1111747Y694163D01*
X1110874Y692121D01*
X1110437Y690371D01*
Y688621D01*
X1110874Y686871D01*
X1111966Y685121D01*
X1113276Y683955D01*
X1114804Y683663D01*
X1116332Y684246D01*
X1117861Y685996D01*
G01X1130339Y683663D02*
Y698538D01*
X1130776Y699996D01*
X1131649Y700871D01*
X1132959Y701163D01*
X1134269Y700580D01*
X1134924Y699121D01*
G01X1132304Y694163D02*
X1127937D01*
G01X1149149Y683080D02*
X1148712Y683371D01*
Y683955D01*
X1149149Y684246D01*
X1149586Y683955D01*
Y683371D01*
X1149149Y683080D01*
G01X1179782Y683663D02*
Y701163D01*
X1185022D01*
X1186769Y700288D01*
X1188079Y698246D01*
X1188516Y695913D01*
X1188079Y693580D01*
X1186987Y691830D01*
X1185022Y690954D01*
X1179782D01*
G01X1201649Y683663D02*
Y701163D01*
G01X1223079Y683663D02*
Y695329D01*
G01Y693288D02*
X1222206Y694454D01*
X1220895Y695038D01*
X1219367Y695329D01*
X1217839Y694746D01*
X1216529Y693580D01*
X1215655Y691830D01*
X1215219Y689496D01*
X1215655Y687163D01*
X1216529Y685413D01*
X1217839Y684246D01*
X1219367Y683663D01*
X1220895Y683955D01*
X1222206Y684829D01*
X1223079Y685996D01*
G01X1232937Y683663D02*
Y695329D01*
G01Y692413D02*
X1233811Y693871D01*
X1235121Y695038D01*
X1236867Y695329D01*
X1238395Y695038D01*
X1239706Y693871D01*
X1240361Y691830D01*
Y683663D01*
G01X1250874Y691538D02*
X1257861D01*
X1257206Y693580D01*
X1256114Y694746D01*
X1254586Y695329D01*
X1253057Y695038D01*
X1251747Y694163D01*
X1250874Y692121D01*
X1250437Y690371D01*
Y688621D01*
X1250874Y686871D01*
X1251966Y685121D01*
X1253276Y683955D01*
X1254804Y683663D01*
X1256332Y684246D01*
X1257861Y685996D01*
G01X1162282Y666513D02*
Y649013D01*
X1171016D01*
G01X1180001Y663596D02*
X1181311Y665346D01*
X1182839Y666221D01*
X1184586Y666513D01*
X1186769Y665930D01*
X1188297Y664471D01*
X1188734Y662722D01*
X1188516Y660971D01*
X1187642Y659513D01*
X1183276Y656596D01*
X1181311Y654555D01*
X1180001Y651637D01*
X1179564Y649013D01*
X1188734D01*
G01X1371949Y660679D02*
Y649013D01*
G01Y665346D02*
X1371512Y665638D01*
Y666221D01*
X1371949Y666513D01*
X1372386Y666221D01*
Y665638D01*
X1371949Y665346D01*
G01X1386174Y651054D02*
X1387266Y649888D01*
X1388794Y649013D01*
X1390104D01*
X1391414Y649596D01*
X1392287Y650471D01*
X1392724Y651637D01*
X1392506Y653388D01*
X1391632Y654263D01*
X1387702Y656013D01*
X1386829Y658055D01*
X1387266Y659513D01*
X1388139Y660388D01*
X1389449Y660679D01*
X1390759Y660388D01*
X1392069Y659513D01*
G01X1419427Y649013D02*
Y666513D01*
X1429471Y649013D01*
Y666513D01*
G01X1441949Y649013D02*
X1440202Y649305D01*
X1438674Y650471D01*
X1437364Y652221D01*
X1436490Y654263D01*
X1436054Y656596D01*
Y658930D01*
X1436490Y661263D01*
X1437364Y663305D01*
X1438674Y665054D01*
X1440202Y666221D01*
X1441949Y666513D01*
X1443695Y666221D01*
X1445224Y665054D01*
X1446534Y663305D01*
X1447408Y661263D01*
X1447844Y658930D01*
Y656596D01*
X1447408Y654263D01*
X1446534Y652221D01*
X1445224Y650471D01*
X1443695Y649305D01*
X1441949Y649013D01*
G01X1459449Y666513D02*
Y649013D01*
G01X1454427Y666513D02*
X1464471D01*
G01X1490737Y660679D02*
Y652513D01*
X1491611Y650471D01*
X1492921Y649305D01*
X1494449Y649013D01*
X1495977Y649305D01*
X1497287Y650471D01*
X1498161Y652513D01*
G01Y649013D02*
Y660679D01*
G01X1508674Y651054D02*
X1509766Y649888D01*
X1511294Y649013D01*
X1512604D01*
X1513914Y649596D01*
X1514787Y650471D01*
X1515224Y651637D01*
X1515006Y653388D01*
X1514132Y654263D01*
X1510202Y656013D01*
X1509329Y658055D01*
X1509766Y659513D01*
X1510639Y660388D01*
X1511949Y660679D01*
X1513259Y660388D01*
X1514569Y659513D01*
G01X1526174Y656888D02*
X1533161D01*
X1532506Y658930D01*
X1531414Y660096D01*
X1529886Y660679D01*
X1528357Y660388D01*
X1527047Y659513D01*
X1526174Y657471D01*
X1525737Y655721D01*
Y653971D01*
X1526174Y652221D01*
X1527266Y650471D01*
X1528576Y649305D01*
X1530104Y649013D01*
X1531632Y649596D01*
X1533161Y651346D01*
G01X1550879Y666513D02*
Y649013D01*
G01Y651637D02*
X1550006Y650179D01*
X1548695Y649305D01*
X1547167Y649013D01*
X1545421Y649596D01*
X1544111Y651054D01*
X1543237Y652804D01*
X1543019Y654846D01*
X1543237Y656888D01*
X1544111Y658638D01*
X1545421Y660096D01*
X1547167Y660679D01*
X1548695Y660388D01*
X1549787Y659804D01*
X1550879Y658638D01*
G01X1297146Y683080D02*
X1306752Y695913D01*
G01X1301949Y698246D02*
Y680746D01*
G01X1306752Y683080D02*
X1297146Y695913D01*
G01X1295399Y689496D02*
X1308499D01*
G01X1334111D02*
X1339787D01*
G01X1367146Y683663D02*
Y701163D01*
X1371512D01*
X1373259Y700288D01*
X1374569Y699121D01*
X1375661Y697372D01*
X1376534Y695329D01*
X1376752Y692413D01*
X1376534Y689496D01*
X1375661Y687454D01*
X1374569Y685704D01*
X1373259Y684538D01*
X1371512Y683663D01*
X1367146D01*
G01X1386174Y691538D02*
X1393161D01*
X1392506Y693580D01*
X1391414Y694746D01*
X1389886Y695329D01*
X1388357Y695038D01*
X1387047Y694163D01*
X1386174Y692121D01*
X1385737Y690371D01*
Y688621D01*
X1386174Y686871D01*
X1387266Y685121D01*
X1388576Y683955D01*
X1390104Y683663D01*
X1391632Y684246D01*
X1393161Y685996D01*
G01X1403237Y683663D02*
Y695329D01*
G01Y692413D02*
X1404111Y693871D01*
X1405421Y695038D01*
X1407167Y695329D01*
X1408695Y695038D01*
X1410006Y693871D01*
X1410661Y691830D01*
Y683663D01*
G01X1424449D02*
X1423139Y683955D01*
X1421829Y685121D01*
X1420955Y687163D01*
X1420519Y689496D01*
X1420955Y691830D01*
X1421829Y693871D01*
X1423139Y695038D01*
X1424449Y695329D01*
X1425759Y695038D01*
X1427069Y693871D01*
X1427942Y691830D01*
X1428161Y689496D01*
X1427942Y687163D01*
X1427069Y685121D01*
X1425759Y683955D01*
X1424449Y683663D01*
G01X1441949Y701163D02*
Y683663D01*
G01X1438892Y695329D02*
X1445006D01*
G01X1456174Y691538D02*
X1463161D01*
X1462506Y693580D01*
X1461414Y694746D01*
X1459886Y695329D01*
X1458357Y695038D01*
X1457047Y694163D01*
X1456174Y692121D01*
X1455737Y690371D01*
Y688621D01*
X1456174Y686871D01*
X1457266Y685121D01*
X1458576Y683955D01*
X1460104Y683663D01*
X1461632Y684246D01*
X1463161Y685996D01*
G01X1473674Y685704D02*
X1474766Y684538D01*
X1476294Y683663D01*
X1477604D01*
X1478914Y684246D01*
X1479787Y685121D01*
X1480224Y686287D01*
X1480006Y688038D01*
X1479132Y688913D01*
X1475202Y690663D01*
X1474329Y692705D01*
X1474766Y694163D01*
X1475639Y695038D01*
X1476949Y695329D01*
X1478259Y695038D01*
X1479569Y694163D01*
G01X1511949Y701163D02*
Y683663D01*
G01X1508892Y695329D02*
X1515006D01*
G01X1525737Y683663D02*
Y701163D01*
G01Y692705D02*
X1526829Y694163D01*
X1527921Y695038D01*
X1529667Y695329D01*
X1530977Y695038D01*
X1532506Y693871D01*
X1533161Y692121D01*
Y683663D01*
G01X1550879D02*
Y695329D01*
G01Y693288D02*
X1550006Y694454D01*
X1548695Y695038D01*
X1547167Y695329D01*
X1545639Y694746D01*
X1544329Y693580D01*
X1543455Y691830D01*
X1543019Y689496D01*
X1543455Y687163D01*
X1544329Y685413D01*
X1545639Y684246D01*
X1547167Y683663D01*
X1548695Y683955D01*
X1550006Y684829D01*
X1550879Y685996D01*
G01X1564449Y701163D02*
Y683663D01*
G01X1561392Y695329D02*
X1567506D01*
G01X1599449Y701163D02*
Y683663D01*
G01X1596392Y695329D02*
X1602506D01*
G01X1613237Y683663D02*
Y701163D01*
G01Y692705D02*
X1614329Y694163D01*
X1615421Y695038D01*
X1617167Y695329D01*
X1618477Y695038D01*
X1620006Y693871D01*
X1620661Y692121D01*
Y683663D01*
G01X1634449Y695329D02*
Y683663D01*
G01Y699996D02*
X1634012Y700288D01*
Y700871D01*
X1634449Y701163D01*
X1634886Y700871D01*
Y700288D01*
X1634449Y699996D01*
G01X1648674Y685704D02*
X1649766Y684538D01*
X1651294Y683663D01*
X1652604D01*
X1653914Y684246D01*
X1654787Y685121D01*
X1655224Y686287D01*
X1655006Y688038D01*
X1654132Y688913D01*
X1650202Y690663D01*
X1649329Y692705D01*
X1649766Y694163D01*
X1650639Y695038D01*
X1651949Y695329D01*
X1653259Y695038D01*
X1654569Y694163D01*
G01X1684329Y701163D02*
X1689569D01*
G01X1686949D02*
Y683663D01*
G01X1684329D02*
X1689569D01*
G01X1697899D02*
Y695329D01*
G01Y692121D02*
X1698554Y693580D01*
X1699646Y694746D01*
X1701174Y695329D01*
X1702702Y694746D01*
X1703794Y693580D01*
X1704449Y692121D01*
Y683663D01*
G01Y692121D02*
X1705104Y693580D01*
X1706195Y694746D01*
X1707724Y695329D01*
X1709252Y694746D01*
X1710344Y693580D01*
X1710999Y691830D01*
Y683663D01*
G01X1718019Y677830D02*
Y695329D01*
G01Y692705D02*
X1719111Y694163D01*
X1720202Y695038D01*
X1721949Y695329D01*
X1723477Y695038D01*
X1725006Y693580D01*
X1725661Y691538D01*
X1725879Y689496D01*
X1725661Y687454D01*
X1725006Y685413D01*
X1723695Y684246D01*
X1721949Y683663D01*
X1720421Y683955D01*
X1718892Y684829D01*
X1718019Y685996D01*
G01X1736174Y691538D02*
X1743161D01*
X1742506Y693580D01*
X1741414Y694746D01*
X1739886Y695329D01*
X1738357Y695038D01*
X1737047Y694163D01*
X1736174Y692121D01*
X1735737Y690371D01*
Y688621D01*
X1736174Y686871D01*
X1737266Y685121D01*
X1738576Y683955D01*
X1740104Y683663D01*
X1741632Y684246D01*
X1743161Y685996D01*
G01X1760879Y701163D02*
Y683663D01*
G01Y686287D02*
X1760006Y684829D01*
X1758695Y683955D01*
X1757167Y683663D01*
X1755421Y684246D01*
X1754111Y685704D01*
X1753237Y687454D01*
X1753019Y689496D01*
X1753237Y691538D01*
X1754111Y693288D01*
X1755421Y694746D01*
X1757167Y695329D01*
X1758695Y695038D01*
X1759787Y694454D01*
X1760879Y693288D01*
G01X1778379Y683663D02*
Y695329D01*
G01Y693288D02*
X1777506Y694454D01*
X1776195Y695038D01*
X1774667Y695329D01*
X1773139Y694746D01*
X1771829Y693580D01*
X1770955Y691830D01*
X1770519Y689496D01*
X1770955Y687163D01*
X1771829Y685413D01*
X1773139Y684246D01*
X1774667Y683663D01*
X1776195Y683955D01*
X1777506Y684829D01*
X1778379Y685996D01*
G01X1788237Y683663D02*
Y695329D01*
G01Y692413D02*
X1789111Y693871D01*
X1790421Y695038D01*
X1792167Y695329D01*
X1793695Y695038D01*
X1795006Y693871D01*
X1795661Y691830D01*
Y683663D01*
G01X1812942Y693871D02*
X1811414Y695038D01*
X1810104Y695329D01*
X1808357Y694746D01*
X1807047Y693580D01*
X1806174Y691538D01*
X1805955Y689496D01*
X1806174Y687454D01*
X1807047Y685704D01*
X1808357Y684246D01*
X1810104Y683663D01*
X1811632Y684246D01*
X1812942Y685413D01*
G01X1823674Y691538D02*
X1830661D01*
X1830006Y693580D01*
X1828914Y694746D01*
X1827386Y695329D01*
X1825857Y695038D01*
X1824547Y694163D01*
X1823674Y692121D01*
X1823237Y690371D01*
Y688621D01*
X1823674Y686871D01*
X1824766Y685121D01*
X1826076Y683955D01*
X1827604Y683663D01*
X1829132Y684246D01*
X1830661Y685996D01*
G01X-11811Y-26378D02*
G03X-7874Y-22441I0J3937D01*
G01X-31496Y-11378D02*
G03X-16496Y-26378I15000J0D01*
G01X0Y-18504D02*
G03X-7874I-3937J0D01*
G01X-11811Y-26378D02*
X-16496D01*
G01X-31496Y727913D02*
Y-11378D01*
G01X-7874Y-18504D02*
Y-22441D01*
G01Y20866D02*
G03X0I3937J0D01*
G01X-14607Y16741D02*
G03I-4291J0D01*
G01X-7874Y175427D02*
Y20866D01*
G01X-11608Y217029D02*
G03X-19685Y205824I3734J-11205D01*
G01X-9118Y209559D02*
G03X-11811Y205824I1244J-3735D01*
G01X-19685Y187877D02*
G03X-11608Y176672I11811J0D01*
G01X-11811Y187877D02*
G03X-9118Y184142I3937J0D01*
G01X-7874Y175427D02*
X-11609Y176672D01*
G01X-2692Y182000D02*
X-9119Y184142D01*
G01X-7874Y218273D02*
X-11609Y217029D01*
G01X-2692Y211701D02*
X-9119Y209559D01*
G01X-7874Y307086D02*
Y218273D01*
G01X-19685Y205824D02*
Y187877D01*
G01X-11811Y205824D02*
Y187877D01*
G01X0Y370079D02*
G03X-7874I-3937J0D01*
G01Y346456D02*
G03X0I3937J0D01*
G01Y307086D02*
G03X-7874I-3937J0D01*
G01Y370079D02*
Y346456D01*
G01Y409449D02*
G03X0I3937J0D01*
G01X-7874Y564010D02*
Y409449D01*
G01X-11608Y605612D02*
G03X-19685Y594406I3735J-11206D01*
G01X-9118Y598141D02*
G03X-11811Y594406I1244J-3735D01*
G01X-19685Y576459D02*
G03X-11608Y565254I11811J0D01*
G01X-11811Y576459D02*
G03X-9118Y572724I3937J0D01*
G01X-7874Y564010D02*
X-11609Y565255D01*
G01X-2692Y570582D02*
X-9119Y572725D01*
G01X-2692Y600284D02*
X-9119Y598141D01*
G01X-19685Y594406D02*
Y576459D01*
G01X-11811Y594406D02*
Y576459D01*
G01X-7874Y606856D02*
X-11609Y605611D01*
G01X-7874Y695669D02*
Y606856D01*
G01X-13215Y723144D02*
G03I-4291J0D01*
G01X-7874Y738976D02*
G03X-11811Y742913I-3937J0D01*
G01X-16496D02*
G03X-31496Y727913I0J-15000D01*
G01X-7874Y735039D02*
G03X0I3937J0D01*
G01Y695669D02*
G03X-7874I-3937J0D01*
G01X-11811Y742913D02*
X-16496D01*
G01X-7874Y738976D02*
Y735039D01*
G01X29075Y-26378D02*
G03X31044Y-24410I0J1969D01*
G01D02*
Y-788D01*
G01X0Y-22441D02*
G03X3937Y-26378I3937J0D01*
G01X0Y178265D02*
Y-22441D01*
G01X3937Y-26378D02*
X29075D01*
G01X44390Y5118D02*
G03I-2658J0D01*
G01X33012Y1181D02*
G03X31044Y-788I0J-1968D01*
G01X33012Y1181D02*
X199666D01*
G01X71407Y128987D02*
G03X76975Y134555I2784J2784D01*
G01X64567Y137457D02*
G03X65720Y134673I3938J0D01*
G01D02*
X94910Y105484D01*
G01X64567Y137457D02*
Y249131D01*
G01X-2692Y211701D02*
G03X0Y215436I-1245J3735D01*
G01Y178265D02*
G03X-2692Y182000I-3937J0D01*
G01X0Y350394D02*
Y215436D01*
G01X64567Y286302D02*
G03X67259Y282567I3937J0D01*
G01Y252866D02*
G03X64567Y249131I1245J-3735D01*
G01X73686Y280425D02*
X67259Y282567D01*
G01X64567Y286302D02*
Y350394D01*
G01X73686Y255008D02*
X67259Y252866D01*
G01X64567Y346456D02*
G03X72441I3937J0D01*
G01Y321260D02*
G03X64567I-3937J0D01*
G01X29075Y362205D02*
G03X31044Y364173I0J1969D01*
G01X0Y366142D02*
G03X3937Y362205I3937J0D01*
G01X31044Y364173D02*
Y387795D01*
G01X0Y566847D02*
Y366142D01*
G01X3937Y362205D02*
X29075D01*
G01X64567Y350394D02*
G03X60630Y354331I-3937J0D01*
G01X3937D02*
G03X0Y350394I0J-3937D01*
G01X60630Y354331D02*
X3937D01*
G01X44390Y393701D02*
G03I-2658J0D01*
G01X33012Y389764D02*
G03X31044Y387795I0J-1968D01*
G01X33012Y389764D02*
X199666D01*
G01X71407Y517570D02*
G03X76975Y523137I2784J2784D01*
G01X64567Y526040D02*
G03X65720Y523256I3938J0D01*
G01D02*
X94910Y494066D01*
G01X64567Y526040D02*
Y637713D01*
G01X-2692Y600283D02*
G03X0Y604019I-1245J3735D01*
G01Y566847D02*
G03X-2692Y570582I-3937J0D01*
G01X64567Y674885D02*
G03X67259Y671150I3937J0D01*
G01Y641448D02*
G03X64567Y637713I1245J-3735D01*
G01X73686Y669007D02*
X67259Y671150D01*
G01X64567Y674885D02*
Y738976D01*
G01X73686Y643591D02*
X67259Y641448D01*
G01X0Y738976D02*
Y604019D01*
G01X64567Y735039D02*
G03X72441I3937J0D01*
G01Y709842D02*
G03X64567I-3937J0D01*
G01Y738976D02*
G03X60630Y742913I-3937J0D01*
G01X3937D02*
G03X0Y738976I0J-3937D01*
G01X60630Y742913D02*
X3937D01*
G01X127362Y78740D02*
G03I-11023J0D01*
G01X118788Y137176D02*
G03I-4291J0D01*
G01X94791Y116738D02*
G03X89224Y111170I-2784J-2784D01*
G01X143454D02*
G03X137886Y116738I-2784J2784D01*
G01X134984Y104331D02*
G03X137768Y105484I0J3938D01*
G01X94910D02*
G03X97694Y104331I2784J2785D01*
G01X137886Y116738D02*
X133353Y112205D01*
G01X166957Y134673D02*
X137768Y105484D01*
G01X94791Y116738D02*
X99325Y112205D01*
G01X72441Y139088D02*
X76975Y134555D01*
G01X72441Y139088D02*
Y246293D01*
G01X133353Y112205D02*
X99325D01*
G01X134984Y104331D02*
X97694D01*
G01X84252Y276690D02*
G03X76175Y287895I-11811J0D01*
G01X76378Y276690D02*
G03X73686Y280425I-3937J0D01*
G01X76175Y247538D02*
G03X84252Y258743I-3734J11205D01*
G01X73686Y255008D02*
G03X76378Y258743I-1245J3735D01*
G01X76176Y287895D02*
X72441Y289140D01*
G01X84252Y258743D02*
Y276690D01*
G01X76378Y258743D02*
Y276690D01*
G01X72441Y289140D02*
Y321260D01*
G01X76176Y247538D02*
X72441Y246293D01*
G01X119874Y329366D02*
G03I-4291J0D01*
G01X76378Y354331D02*
G03X72441Y350394I0J-3937D01*
G01X76378Y354331D02*
X156299D01*
G01X72441Y346456D02*
Y350394D01*
G01X118788Y525759D02*
G03I-4291J0D01*
G01X94791Y505321D02*
G03X89224Y499753I-2784J-2784D01*
G01X143454D02*
G03X137886Y505321I-2784J2784D01*
G01D02*
X133353Y500787D01*
G01X94791Y505321D02*
X99325Y500787D01*
G01X72441Y527671D02*
X76975Y523137D01*
G01X133353Y500787D02*
X99325D01*
G01X134984Y492913D02*
G03X137768Y494066I0J3938D01*
G01X127362Y467323D02*
G03I-11023J0D01*
G01X94910Y494066D02*
G03X97694Y492913I2784J2785D01*
G01X166957Y523256D02*
X137768Y494066D01*
G01X134984Y492913D02*
X97694D01*
G01X72441Y527671D02*
Y634876D01*
G01X84252Y665272D02*
G03X76175Y676478I-11812J0D01*
G01Y636120D02*
G03X84252Y647326I-3735J11206D01*
G01X76176Y676477D02*
X72441Y677722D01*
G01X84252Y647326D02*
Y665272D01*
G01X72441Y677722D02*
Y709842D01*
G01X76176Y636121D02*
X72441Y634876D01*
G01X76378Y665272D02*
G03X73686Y669007I-3937J0D01*
G01Y643591D02*
G03X76378Y647326I-1245J3735D01*
G01D02*
Y665272D01*
G01X119874Y717948D02*
G03I-4291J0D01*
G01X76378Y742913D02*
G03X72441Y738976I0J-3937D01*
G01X76378Y742913D02*
X156299D01*
G01X72441Y735039D02*
Y738976D01*
G01X201634Y-24410D02*
G03X203603Y-26378I1968J0D01*
G01X201634Y-788D02*
Y-24410D01*
G01X203603Y-26378D02*
X228740D01*
G01X193603Y5118D02*
G03I-2658J0D01*
G01X201634Y-788D02*
G03X199666Y1181I-1969J0D01*
G01X155703Y134555D02*
G03X161271Y128987I2784J-2784D01*
G01X166957Y134673D02*
G03X168110Y137457I-2785J2784D01*
G01X160236Y139088D02*
X155703Y134555D01*
G01X160236Y246293D02*
Y139088D01*
G01X168110Y249131D02*
Y137457D01*
G01X165418Y282567D02*
G03X168110Y286302I-1245J3735D01*
G01X156502Y287895D02*
G03X148425Y276690I3734J-11205D01*
G01X158992Y280425D02*
G03X156299Y276690I1244J-3735D01*
G01X168110Y249131D02*
G03X165418Y252866I-3937J0D01*
G01X148425Y258743D02*
G03X156502Y247538I11811J0D01*
G01X156299Y258743D02*
G03X158992Y255008I3937J0D01*
G01X160236Y246293D02*
X156501Y247538D01*
G01X165418Y252866D02*
X158991Y255008D01*
G01X160236Y321260D02*
Y289140D01*
G01X168110Y350394D02*
Y286302D01*
G01X148425Y276690D02*
Y258743D01*
G01X156299Y276690D02*
Y258743D01*
G01X160236Y289140D02*
X156501Y287895D01*
G01X165418Y282567D02*
X158991Y280425D01*
G01X225227Y362205D02*
G03Y354331I0J-3937D01*
G01X207116D02*
G03Y362205I0J3937D01*
G01X160236Y346456D02*
G03X168110I3937J0D01*
G01Y321260D02*
G03X160236I-3937J0D01*
G01Y350394D02*
G03X156299Y354331I-3937J0D01*
G01X201634Y364173D02*
G03X203603Y362205I1968J0D01*
G01X201634Y387795D02*
Y364173D01*
G01X203603Y362205D02*
X228740D01*
G01X172047Y354331D02*
G03X168110Y350394I0J-3937D01*
G01X228740Y354331D02*
X172047D01*
G01X160236Y350394D02*
Y346456D01*
G01X193603Y393701D02*
G03I-2658J0D01*
G01X201634Y387795D02*
G03X199666Y389764I-1969J0D01*
G01X155703Y523137D02*
G03X161271Y517570I2784J-2783D01*
G01X160236Y527671D02*
X155703Y523137D01*
G01X166957Y523256D02*
G03X168110Y526040I-2785J2784D01*
G01Y637713D02*
Y526040D01*
G01X160236Y634876D02*
Y527671D01*
G01X156502Y676478D02*
G03X148425Y665272I3735J-11206D01*
G01Y647326D02*
G03X156502Y636120I11812J0D01*
G01X160236Y634876D02*
X156501Y636121D01*
G01X160236Y709842D02*
Y677722D01*
G01X148425Y665272D02*
Y647326D01*
G01X160236Y677722D02*
X156501Y676477D01*
G01X165418Y671150D02*
G03X168110Y674885I-1245J3735D01*
G01X158992Y669007D02*
G03X156299Y665272I1244J-3735D01*
G01X168110Y637713D02*
G03X165418Y641448I-3937J0D01*
G01X156299Y647326D02*
G03X158992Y643591I3937J0D01*
G01X165418Y641448D02*
X158991Y643591D01*
G01X168110Y738976D02*
Y674885D01*
G01X156299Y665272D02*
Y647326D01*
G01X165418Y671150D02*
X158991Y669007D01*
G01X160236Y735039D02*
G03X168110I3937J0D01*
G01Y709842D02*
G03X160236I-3937J0D01*
G01Y738976D02*
G03X156299Y742913I-3937J0D01*
G01X160236Y738976D02*
Y735039D01*
G01X172047Y742913D02*
G03X168110Y738976I0J-3937D01*
G01X228740Y742913D02*
X172047D01*
G01X236614Y-14567D02*
X244488D01*
G01X236614D02*
G03X232677Y-18504I0J-3937D01*
G01X248425D02*
G03X244488Y-14567I-3937J0D01*
G01X248425Y-22441D02*
G03X252362Y-26378I3937J0D01*
G01D02*
X309055D01*
G01X248425Y112921D02*
Y-22441D01*
G01X228740Y-26378D02*
G03X232677Y-22441I0J3937D01*
G01D02*
Y178669D01*
G01X236614Y16929D02*
X244488D01*
G01X232677Y20866D02*
G03X236614Y16929I3937J0D01*
G01X244488D02*
G03X248425Y20866I0J3937D01*
G01X246249Y145762D02*
G03X248425Y149283I-1761J3521D01*
G01Y112921D02*
G03X246249Y116442I-3937J0D01*
G01X242727Y144001D02*
G03X240551Y140480I1761J-3521D01*
G01Y121724D02*
G03X242727Y118203I3937J0D01*
G01X240551Y140480D02*
Y121724D01*
G01X242728Y118203D02*
X246249Y116442D01*
G01X242728Y144001D02*
X246249Y145762D01*
G01X248425Y350394D02*
Y149283D01*
G01X234853Y182190D02*
G03X232677Y178669I1761J-3521D01*
G01Y215031D02*
G03X234853Y211510I3937J0D01*
G01X238375Y183951D02*
G03X240551Y187472I-1761J3521D01*
G01Y206228D02*
G03X238375Y209749I-3937J0D01*
G01X240551Y187472D02*
Y206228D01*
G01X232677Y215031D02*
Y350394D01*
G01X238375Y209749D02*
X234854Y211510D01*
G01X238375Y183951D02*
X234854Y182190D01*
G01X273986Y362205D02*
G03Y354331I0J-3937D01*
G01X255876D02*
G03Y362205I0J3937D01*
G01X236614Y374016D02*
X244488D01*
G01X236614D02*
G03X232677Y370079I0J-3937D01*
G01X248425D02*
G03X244488Y374016I-3937J0D01*
G01X236614Y342519D02*
X244488D01*
G01X236614Y311023D02*
X244488D01*
G01X236614D02*
G03X232677Y307086I0J-3937D01*
G01Y346456D02*
G03X236614Y342519I3937J0D01*
G01X244488D02*
G03X248425Y346456I0J3937D01*
G01Y307086D02*
G03X244488Y311023I-3937J0D01*
G01X248425Y366142D02*
G03X252362Y362205I3937J0D01*
G01D02*
X309055D01*
G01X248425Y501504D02*
Y366142D01*
G01X228740Y362205D02*
G03X232677Y366142I0J3937D01*
G01D02*
Y567252D01*
G01X279469Y352362D02*
G03X277500Y354331I-1969J0D01*
G01X252362D02*
G03X248425Y350394I0J-3937D01*
G01X292815Y322834D02*
G03I-2657J0D01*
G01X279469Y328740D02*
G03X281437Y326771I1969J0D01*
G01X279469Y328740D02*
Y352362D01*
G01X448091Y326771D02*
X281437D01*
G01X277500Y354331D02*
X252362D01*
G01X232677Y350394D02*
G03X228740Y354331I-3937J0D01*
G01X236614Y405512D02*
X244488D01*
G01X232677Y409449D02*
G03X236614Y405512I3937J0D01*
G01X244488D02*
G03X248425Y409449I0J3937D01*
G01Y501504D02*
G03X246249Y505025I-3937J0D01*
G01X240551Y510307D02*
G03X242727Y506786I3937J0D01*
G01X240551Y529063D02*
Y510307D01*
G01X242728Y506786D02*
X246249Y505025D01*
G01Y534345D02*
G03X248425Y537866I-1761J3521D01*
G01X242727Y532584D02*
G03X240551Y529063I1761J-3521D01*
G01X248425Y738976D02*
Y537866D01*
G01X242728Y532584D02*
X246249Y534345D01*
G01X234853Y570773D02*
G03X232677Y567252I1761J-3521D01*
G01Y603614D02*
G03X234853Y600093I3937J0D01*
G01X238375Y572534D02*
G03X240551Y576055I-1761J3521D01*
G01Y594811D02*
G03X238375Y598332I-3937J0D01*
G01X240551Y576055D02*
Y594811D01*
G01X238375Y598332D02*
X234854Y600093D01*
G01X238375Y572534D02*
X234854Y570773D01*
G01X232677Y603614D02*
Y738976D01*
G01X236614Y731102D02*
X244488D01*
G01X236614Y699606D02*
X244488D01*
G01X236614D02*
G03X232677Y695669I0J-3937D01*
G01Y735039D02*
G03X236614Y731102I3937J0D01*
G01X244488D02*
G03X248425Y735039I0J3937D01*
G01Y695669D02*
G03X244488Y699606I-3937J0D01*
G01X279469Y740945D02*
G03X277500Y742913I-1968J0D01*
G01X252362D02*
G03X248425Y738976I0J-3937D01*
G01X292815Y711417D02*
G03I-2657J0D01*
G01X279469Y717323D02*
G03X281437Y715354I1969J0D01*
G01X279469Y717323D02*
Y740945D01*
G01X448091Y715354D02*
X281437D01*
G01X277500Y742913D02*
X252362D01*
G01X232677Y738976D02*
G03X228740Y742913I-3937J0D01*
G01X369811Y-1413D02*
G03I-4291J0D01*
G01X320866Y-18504D02*
G03X312992I-3937J0D01*
G01X320866Y-22441D02*
G03X324803Y-26378I3937J0D01*
G01X404725D02*
X324803D01*
G01X320866Y-22441D02*
Y-18504D01*
G01X309055Y-26378D02*
G03X312992Y-22441I0J3937D01*
G01D02*
Y41650D01*
G01Y6693D02*
G03X320866I3937J0D01*
G01X324600Y40057D02*
G03X332677Y51263I-3735J11206D01*
G01Y69209D02*
G03X324600Y80415I-11812J0D01*
G01X320866Y6693D02*
Y38813D01*
G01X332677Y51263D02*
Y69209D01*
G01X320866Y38813D02*
X324601Y40058D01*
G01X315685Y45385D02*
G03X312992Y41650I1244J-3735D01*
G01X322111Y47528D02*
G03X324803Y51263I-1245J3735D01*
G01Y69209D02*
G03X322111Y72944I-3937J0D01*
G01X324803Y51263D02*
Y69209D01*
G01X315684Y45385D02*
X322111Y47528D01*
G01X320866Y81659D02*
X324601Y80414D01*
G01X320866Y81659D02*
Y188864D01*
G01X312992Y78822D02*
G03X315685Y75087I3937J0D01*
G01X315684D02*
X322111Y72944D01*
G01X312992Y78822D02*
Y190495D01*
G01X370897Y190776D02*
G03I-4291J0D01*
G01X337649Y216782D02*
G03X343217Y211214I2784J-2784D01*
G01X325400Y193398D02*
G03X319832Y198965I-2784J2784D01*
G01X343217Y211214D02*
X347750Y215748D01*
G01X320866Y188864D02*
X325400Y193398D01*
G01X347750Y215748D02*
X381778D01*
G01X314145Y193279D02*
G03X312992Y190495I2785J-2784D01*
G01X346119Y223622D02*
G03X343335Y222469I0J-3938D01*
G01X314145Y193279D02*
X343335Y222469D01*
G01X375788Y249212D02*
G03I-11024J0D01*
G01X346119Y223622D02*
X383409D01*
G01X320866Y370079D02*
G03X312992I-3937J0D01*
G01X320866Y366142D02*
G03X324803Y362205I3937J0D01*
G01X404725D02*
X324803D01*
G01X320866Y366142D02*
Y370079D01*
G01X309055Y362205D02*
G03X312992Y366142I0J3937D01*
G01D02*
Y430233D01*
G01X369811Y387169D02*
G03I-4291J0D01*
G01X312992Y395275D02*
G03X320866I3937J0D01*
G01X324600Y428640D02*
G03X332677Y439845I-3734J11205D01*
G01X320866Y395275D02*
Y427395D01*
G01X332677Y439845D02*
Y457792D01*
G01X320866Y427395D02*
X324601Y428640D01*
G01X315685Y433968D02*
G03X312992Y430233I1244J-3735D01*
G01X322111Y436110D02*
G03X324803Y439845I-1245J3735D01*
G01D02*
Y457792D01*
G01X315684Y433968D02*
X322111Y436110D01*
G01X332677Y457792D02*
G03X324600Y468997I-11811J0D01*
G01X320866Y470242D02*
X324601Y468997D01*
G01X320866Y470242D02*
Y577447D01*
G01X312992Y467404D02*
G03X315685Y463669I3937J0D01*
G01X324803Y457792D02*
G03X322111Y461527I-3937J0D01*
G01X315684Y463669D02*
X322111Y461527D01*
G01X312992Y467404D02*
Y579078D01*
G01X370897Y579359D02*
G03I-4291J0D01*
G01X337649Y605365D02*
G03X343217Y599797I2784J-2784D01*
G01X325400Y581980D02*
G03X319832Y587548I-2784J2784D01*
G01X343217Y599797D02*
X347750Y604331D01*
G01X320866Y577447D02*
X325400Y581980D01*
G01X314145Y581862D02*
G03X312992Y579078I2785J-2784D01*
G01X314145Y581862D02*
X343335Y611051D01*
G01X347750Y604331D02*
X381778D01*
G01X346119Y612205D02*
G03X343335Y611051I1J-3937D01*
G01X375788Y637795D02*
G03I-11024J0D01*
G01X346119Y612205D02*
X383409D01*
G01X416536Y-18504D02*
G03X408662I-3937J0D01*
G01X404725Y-26378D02*
G03X408662Y-22441I0J3937D01*
G01Y-18504D02*
Y-22441D01*
G01X416536D02*
G03X420473Y-26378I3937J0D01*
G01D02*
X477166D01*
G01X416536Y41650D02*
Y-22441D01*
G01X408662Y6693D02*
G03X416536I3937J0D01*
G01X396851Y51263D02*
G03X404928Y40057I11812J0D01*
G01Y80415D02*
G03X396851Y69209I3735J-11206D01*
G01X404927Y40058D02*
X408662Y38813D01*
G01X396851Y69209D02*
Y51263D01*
G01X408662Y38813D02*
Y6693D01*
G01X416536Y41650D02*
G03X413843Y45385I-3937J0D01*
G01X404725Y51263D02*
G03X407417Y47528I3937J0D01*
G01Y72944D02*
G03X404725Y69209I1245J-3735D01*
G01X407417Y47528D02*
X413844Y45385D01*
G01X404725Y69209D02*
Y51263D01*
G01X408662Y188864D02*
Y81659D01*
G01X404927Y80414D02*
X408662Y81659D01*
G01X413843Y75087D02*
G03X416536Y78822I-1244J3735D01*
G01Y190495D02*
Y78822D01*
G01X407417Y72944D02*
X413844Y75087D01*
G01X409696Y198965D02*
G03X404128Y193398I-2784J-2783D01*
G01X386311Y211214D02*
G03X391879Y216782I2784J2784D01*
G01X386311Y211214D02*
X381778Y215748D01*
G01X408662Y188864D02*
X404128Y193398D01*
G01X386193Y222469D02*
G03X383409Y223622I-2784J-2785D01*
G01X416536Y190495D02*
G03X415383Y193279I-3938J0D01*
G01D02*
X386193Y222469D01*
G01X416536Y370079D02*
G03X408662I-3937J0D01*
G01X404725Y362205D02*
G03X408662Y366142I0J3937D01*
G01Y370079D02*
Y366142D01*
G01X416536D02*
G03X420473Y362205I3937J0D01*
G01D02*
X477166D01*
G01X416536Y430233D02*
Y366142D01*
G01X442028Y322834D02*
G03I-2658J0D01*
G01X448091Y326771D02*
G03X450059Y328740I0J1968D01*
G01X452028Y354331D02*
G03X450059Y352362I0J-1969D01*
G01D02*
Y328740D01*
G01X408662Y395275D02*
G03X416536I3937J0D01*
G01X396851Y439845D02*
G03X404928Y428640I11811J0D01*
G01X404927D02*
X408662Y427395D01*
G01X396851Y457792D02*
Y439845D01*
G01X408662Y427395D02*
Y395275D01*
G01X416536Y430233D02*
G03X413843Y433968I-3937J0D01*
G01X404725Y439845D02*
G03X407417Y436110I3937J0D01*
G01D02*
X413844Y433968D01*
G01X404725Y457792D02*
Y439845D01*
G01X404928Y468997D02*
G03X396851Y457792I3734J-11205D01*
G01X408662Y577447D02*
Y470242D01*
G01X404927Y468997D02*
X408662Y470242D01*
G01X413843Y463669D02*
G03X416536Y467404I-1244J3735D01*
G01X407417Y461527D02*
G03X404725Y457792I1245J-3735D01*
G01X416536Y579078D02*
Y467404D01*
G01X407417Y461527D02*
X413844Y463669D01*
G01X409696Y587548D02*
G03X404128Y581980I-2784J-2784D01*
G01X386311Y599797D02*
G03X391879Y605365I2784J2784D01*
G01X386311Y599797D02*
X381778Y604331D01*
G01X408662Y577447D02*
X404128Y581980D01*
G01X416536Y579078D02*
G03X415383Y581862I-3938J0D01*
G01D02*
X386193Y611051D01*
G01D02*
G03X383409Y612205I-2785J-2783D01*
G01X442028Y711417D02*
G03I-2658J0D01*
G01X448091Y715354D02*
G03X450059Y717323I0J1968D01*
G01X452028Y742913D02*
G03X450059Y740945I0J-1969D01*
G01D02*
Y717323D01*
G01X488977Y-22441D02*
G03X492914Y-26378I3937J0D01*
G01X497599D02*
G03X512599Y-11378I0J15000D01*
G01X488977Y-18504D02*
G03X481103I-3937J0D01*
G01X492914Y-26378D02*
X497599D01*
G01X512599Y-11378D02*
Y455139D01*
G01X488977Y-22441D02*
Y-18504D01*
G01X477166Y-26378D02*
G03X481103Y-22441I0J3937D01*
G01D02*
Y112517D01*
G01Y20866D02*
G03X488977I3937J0D01*
G01D02*
Y109679D01*
G01X492711Y110924D02*
G03X500788Y122129I-3734J11205D01*
G01Y140076D02*
G03X492711Y151281I-11811J0D01*
G01X488977Y109679D02*
X492712Y110924D01*
G01X500788Y122129D02*
Y140076D01*
G01X483795Y116252D02*
G03X481103Y112517I1245J-3735D01*
G01Y149688D02*
G03X483795Y145953I3937J0D01*
G01X490221Y118394D02*
G03X492914Y122129I-1244J3735D01*
G01Y140076D02*
G03X490221Y143811I-3937J0D01*
G01X483795Y145953D02*
X490222Y143811D01*
G01X483795Y116251D02*
X490222Y118394D01*
G01X492914Y122129D02*
Y140076D01*
G01X488977Y152525D02*
X492712Y151280D01*
G01X488977Y152525D02*
Y307086D01*
G01X481103Y149688D02*
Y350394D01*
G01X488977Y307086D02*
G03X481103I-3937J0D01*
G01Y346456D02*
G03X488977I3937J0D01*
G01Y370079D02*
G03X481103I-3937J0D01*
G01X488977Y346456D02*
Y370079D01*
G01X477166Y362205D02*
G03X481103Y366142I0J3937D01*
G01D02*
Y501099D01*
G01Y350394D02*
G03X477166Y354331I-3937J0D01*
G01D02*
X452028D01*
G01X481103Y409449D02*
G03X488977I3937J0D01*
G01D02*
Y498262D01*
G01X512599Y463013D02*
G03Y455139I0J-3937D01*
G01Y463013D02*
Y727913D01*
G01X492711Y499506D02*
G03X500788Y510711I-3734J11205D01*
G01X488977Y498262D02*
X492712Y499507D01*
G01X500788Y510711D02*
Y528658D01*
G01X483795Y504834D02*
G03X481103Y501099I1245J-3735D01*
G01X490221Y506976D02*
G03X492914Y510711I-1244J3735D01*
G01X483795Y504834D02*
X490222Y506976D01*
G01X492914Y510711D02*
Y528658D01*
G01X500788D02*
G03X492711Y539863I-11811J0D01*
G01X488977Y541108D02*
X492712Y539863D01*
G01X488977Y541108D02*
Y695669D01*
G01X481103Y538271D02*
G03X483795Y534535I3937J-1D01*
G01X492914Y528658D02*
G03X490221Y532393I-3937J0D01*
G01X483795Y534536D02*
X490222Y532393D01*
G01X481103Y538271D02*
Y738976D01*
G01X499107Y713716D02*
G03I-4291J0D01*
G01X492914Y742913D02*
G03X488977Y738976I0J-3937D01*
G01X512599Y727913D02*
G03X497599Y742913I-15000J0D01*
G01X488977Y695669D02*
G03X481103I-3937J0D01*
G01Y735039D02*
G03X488977I3937J0D01*
G01X492914Y742913D02*
X497599D01*
G01X488977Y735039D02*
Y738976D01*
G01X481103D02*
G03X477166Y742913I-3937J0D01*
G01D02*
X452028D01*
G54D12*
G01X61000Y68900D02*
Y60500D01*
G01X54240Y75660D02*
X61000Y68900D01*
G01Y57900D02*
Y60500D01*
G01X58700Y55600D02*
X61000Y57900D01*
G01X72040Y70540D02*
X75604Y74104D01*
G01X69500Y70540D02*
X72040D01*
G01X40231Y66704D02*
X40631Y67104D01*
G01X36981Y66704D02*
X40231D01*
G01X43077Y73100D02*
X40781Y70804D01*
G01Y67254D02*
X40631Y67104D01*
G01X40781Y70804D02*
Y67254D01*
G01X29650Y64650D02*
Y66500D01*
G01X31700Y62600D02*
X29650Y64650D01*
G01X33450Y62600D02*
X31700D01*
G01X29650Y74850D02*
Y70800D01*
G01D02*
Y66500D01*
G01X36950Y62600D02*
X41300D01*
G01X43462Y64762D02*
X41300Y62600D01*
G01X43462Y66862D02*
Y64762D01*
G01X44580Y67980D02*
X43462Y66862D01*
G01X47300Y67980D02*
X44580D01*
G01X29400Y58000D02*
Y58900D01*
G01X31938Y55462D02*
X29400Y58000D01*
G01X45262Y55462D02*
X31938D01*
G01X48250Y58450D02*
X45262Y55462D01*
G01X48250Y59700D02*
Y58450D01*
G01X25650Y74634D02*
Y70800D01*
G01Y62650D02*
X29400Y58900D01*
G01X25650Y70800D02*
Y62650D01*
G01X61630Y45565D02*
X64450D01*
G01X59500Y47695D02*
X61630Y45565D01*
G01X59500Y51900D02*
Y47695D01*
G01X61035Y53435D02*
X59500Y51900D01*
G01X64450Y53435D02*
X61035D01*
G01X71265D02*
X64450D01*
G01X71500Y53200D02*
X71265Y53435D01*
G01X73800Y50900D02*
X71500Y53200D01*
G01X55200Y59700D02*
X56000Y60500D01*
G01X51750Y59700D02*
X55200D01*
G01X56500Y61000D02*
X56000Y60500D01*
G01X56500Y66100D02*
Y61000D01*
G01X52060Y70540D02*
X56500Y66100D01*
G01X47300Y70540D02*
X52060D01*
G01X47060Y37060D02*
Y32450D01*
G01X48000Y38000D02*
X47060Y37060D01*
G01X52500Y32300D02*
X53250D01*
G01X51400Y31200D02*
X52500Y32300D01*
G01X48310Y31200D02*
X51400D01*
G01X47060Y32450D02*
X48310Y31200D01*
G01X62440Y27160D02*
Y25750D01*
G01X59862Y29738D02*
X62440Y27160D01*
G01X56084Y29738D02*
X59862D01*
G01X55434Y30388D02*
X56084Y29738D01*
G01X55162Y30388D02*
X55434D01*
G01X53250Y32300D02*
X55162Y30388D01*
G01X69500Y67980D02*
X73200D01*
G01X65500Y60900D02*
X66200Y60200D01*
G01X65500Y64400D02*
Y60900D01*
G01X66520Y65420D02*
X65500Y64400D01*
G01X69500Y65420D02*
X66520D01*
G01X66400Y60000D02*
X66200Y60200D01*
G01X69550Y60000D02*
X66400D01*
G01X70050Y60500D02*
X69550Y60000D01*
G01X73857Y105600D02*
X69150D01*
G01X59940Y107940D02*
X58250D01*
G01X61900Y109900D02*
X59940Y107940D01*
G01X61900Y115100D02*
Y109900D01*
G01X60588Y116412D02*
X61900Y115100D01*
G01X60588Y121233D02*
Y116412D01*
G01X57082Y124739D02*
X60588Y121233D01*
G01X54318Y124739D02*
X57082D01*
G01X53079Y123500D02*
X54318Y124739D01*
G01X35650Y123500D02*
X53079D01*
G01X33700Y121550D02*
X35650Y123500D01*
G01X59200Y105600D02*
X69150D01*
G01X58250Y106550D02*
X59200Y105600D01*
G01X58250Y107940D02*
Y106550D01*
G01X47300Y75660D02*
X54240D01*
G01X20155Y73626D02*
X16174D01*
G01X21600Y75071D02*
X20155Y73626D01*
G01X21600Y76660D02*
Y75071D01*
G01X15724Y73626D02*
X12100Y77250D01*
G01X16174Y73626D02*
X15724D01*
G01X12100Y77250D02*
X9000D01*
G01X36652Y109358D02*
X37992D01*
G01X36180Y109830D02*
X36652Y109358D01*
G01X34570Y109830D02*
X36180D01*
G01X34148Y110252D02*
X34570Y109830D01*
G01X31500Y110252D02*
X34148D01*
G01X36900Y113400D02*
X37000Y113300D01*
G01X36900Y117150D02*
Y113400D01*
G01X38250Y118500D02*
X36900Y117150D01*
G01X37992Y112308D02*
X37000Y113300D01*
G01X37992Y109358D02*
Y112308D01*
G01X47300Y73100D02*
X43077D01*
G01X37527Y102920D02*
X45314D01*
G01X32526Y97919D02*
X37527Y102920D01*
G01X10788Y97919D02*
X32526D01*
G01X6413Y102294D02*
X10788Y97919D01*
G01X6413Y181519D02*
Y102294D01*
G01X45319Y102925D02*
X45314Y102920D01*
G01X56075Y102925D02*
X45319D01*
G01X57000Y102000D02*
X56075Y102925D01*
G01X73673Y102000D02*
X57000D01*
G01X31460Y76660D02*
X29650Y74850D01*
G01X34400Y76660D02*
X31460D01*
G01X60188Y130563D02*
Y162912D01*
G01X60162Y130537D02*
X60188Y130563D01*
G01X60162Y129227D02*
Y130537D01*
G01X93762Y95627D02*
X60162Y129227D01*
G01X41500Y95400D02*
X41200Y95100D01*
G01X42900Y95400D02*
X41500D01*
G01X44720Y93580D02*
X42900Y95400D01*
G01X47300Y93580D02*
X44720D01*
G01X39250Y93150D02*
Y91400D01*
G01X41200Y95100D02*
X39250Y93150D01*
G01X46900Y110500D02*
X51750D01*
G01X46200Y111200D02*
X46900Y110500D01*
G01X40900Y89750D02*
Y88400D01*
G01X39250Y91400D02*
X40900Y89750D01*
G01X9761Y95162D02*
X27042D01*
G01X3738Y101185D02*
X9761Y95162D01*
G01X3738Y183938D02*
Y101185D01*
G01X37195Y98804D02*
X73085D01*
G01X33553Y95162D02*
X37195Y98804D01*
G01X27042Y95162D02*
X33553D01*
G01X22322Y100738D02*
X23093Y99967D01*
G01X11753Y100738D02*
X22322D01*
G01X9088Y103403D02*
X11753Y100738D01*
G01X9088Y153972D02*
Y103403D01*
G01X57513Y131672D02*
Y152966D01*
G01X57487Y131646D02*
X57513Y131672D01*
G01X57487Y128118D02*
Y131646D01*
G01X63263Y122342D02*
X57487Y128118D01*
G01X63263Y118253D02*
Y122342D01*
G01X67282Y114234D02*
X63263Y118253D01*
G01X69316Y112200D02*
X67282Y114234D01*
G01X71041Y112200D02*
X69316D01*
G01X91089Y92152D02*
X71041Y112200D01*
G01X30236Y79220D02*
X25650Y74634D01*
G01X34400Y79220D02*
X30236D01*
G01X45900Y116200D02*
Y118700D01*
G01X49040Y113060D02*
X45900Y116200D01*
G01X51750Y113060D02*
X49040D01*
G01X34016Y118050D02*
X33700D01*
G01X36791Y120825D02*
X34016Y118050D01*
G01X44023Y120825D02*
X36791D01*
G01X45900Y118948D02*
X44023Y120825D01*
G01X45900Y118700D02*
Y118948D01*
G01X29058Y114342D02*
Y112222D01*
G01X28200Y115200D02*
X29058Y114342D01*
G01X28200Y117850D02*
Y115200D01*
G01X28400Y118050D02*
X28200Y117850D01*
G01X33700Y118050D02*
X28400D01*
G01X28000Y89600D02*
X24900D01*
G01X29400Y88200D02*
X28000Y89600D01*
G01X29400Y85100D02*
Y88200D01*
G01X30160Y84340D02*
X29400Y85100D01*
G01X34400Y84340D02*
X30160D01*
G01X22300Y89600D02*
X24900D01*
G01X20382Y91518D02*
X22300Y89600D01*
G01X20382Y91581D02*
Y91518D01*
G01X19763Y92200D02*
X20382Y91581D01*
G01X14150Y106250D02*
X17700D01*
G01X12900Y107500D02*
X14150Y106250D01*
G01X21050Y109250D02*
X23300D01*
G01X18050Y106250D02*
X21050Y109250D01*
G01X17700Y106250D02*
X18050D01*
G01X12014Y108386D02*
Y153114D01*
G01X12900Y107500D02*
X12014Y108386D01*
G01X16633Y146653D02*
X47933D01*
G01Y149733D02*
Y146653D01*
G01X16598Y146688D02*
X16633Y146653D01*
G01X16598Y154767D02*
Y146688D01*
G01X25818Y108282D02*
X29058D01*
G01X24850Y109250D02*
X25818Y108282D01*
G01X23300Y109250D02*
X24850D01*
G01X18600Y78400D02*
X15800D01*
G01X19420Y79220D02*
X18600Y78400D01*
G01X21600Y79220D02*
X19420D01*
G01X14950Y78400D02*
X12100Y81250D01*
G01X15800Y78400D02*
X14950D01*
G01X12100Y81250D02*
X9000D01*
G01X19315Y163381D02*
X20539D01*
G01X16538Y166158D02*
X19315Y163381D01*
G01X16538Y167477D02*
Y166158D01*
G01X8392Y211523D02*
Y207860D01*
G01X28346Y231477D02*
X8392Y211523D01*
G01X17020Y191720D02*
X13200Y187900D01*
G01X21010Y191720D02*
X17020D01*
G01X8839Y183945D02*
X6413Y181519D01*
G01X8839Y191539D02*
Y183945D01*
G01X9050Y191750D02*
X8839Y191539D01*
G01X29371Y159738D02*
X29232Y159877D01*
G01X33609Y159738D02*
X29371D01*
G01X28240Y172271D02*
X27283Y173228D01*
G01X28240Y160869D02*
Y172271D01*
G01X29232Y159877D02*
X28240Y160869D01*
G01X44750Y188110D02*
Y187610D01*
G01X41140Y191720D02*
X44750Y188110D01*
G01X37190Y191720D02*
X41140D01*
G01X50991Y181874D02*
X54492D01*
G01X50278Y182587D02*
X50991Y181874D01*
G01X50273Y182587D02*
X50278D01*
G01X49322Y183538D02*
X50273Y182587D01*
G01X46533Y183538D02*
X49322D01*
G01X44750Y185321D02*
X46533Y183538D01*
G01X44750Y187610D02*
Y185321D01*
G01X57962Y165138D02*
X55300D01*
G01X60188Y162912D02*
X57962Y165138D01*
G01X45373D02*
X55300D01*
G01X37283Y173228D02*
X45373Y165138D01*
G01X4400Y184600D02*
X3738Y183938D01*
G01X4400Y196450D02*
Y184600D01*
G01X7200Y199250D02*
X4400Y196450D01*
G01X20653Y159819D02*
X17323D01*
G01X22890Y162056D02*
X20653Y159819D01*
G01X22890Y167255D02*
Y162056D01*
G01X21029Y169116D02*
X22890Y167255D01*
G01X21029Y177870D02*
Y169116D01*
G01X29515Y186356D02*
X21029Y177870D01*
G01X29515Y198910D02*
Y186356D01*
G01X33379Y202774D02*
X29515Y198910D01*
G01X36793Y202774D02*
X33379D01*
G01X38760Y204741D02*
X36793Y202774D01*
G01X44635Y204741D02*
X38760D01*
G01X56061Y216167D02*
X44635Y204741D01*
G01X56061Y270855D02*
Y216167D01*
G01X14935Y159819D02*
X9088Y153972D01*
G01X17323Y159819D02*
X14935D01*
G01X10520Y217435D02*
X10519D01*
G01X22960Y229875D02*
X10520Y217435D01*
G01X58736Y215058D02*
Y271964D01*
G01X45744Y202066D02*
X58736Y215058D01*
G01X39869Y202066D02*
X45744D01*
G01X37902Y200099D02*
X39869Y202066D01*
G01X34488Y200099D02*
X37902D01*
G01X32190Y197801D02*
X34488Y200099D01*
G01X32190Y185247D02*
Y197801D01*
G01X23704Y176761D02*
X32190Y185247D01*
G01X23704Y170643D02*
Y176761D01*
G01X25565Y168782D02*
X23704Y170643D01*
G01X25565Y159579D02*
Y168782D01*
G01X30644Y154500D02*
X25565Y159579D01*
G01X39711Y154500D02*
X30644D01*
G01X42716Y157505D02*
X39711Y154500D01*
G01X52974Y157505D02*
X42716D01*
G01X57513Y152966D02*
X52974Y157505D01*
G01X14002Y213349D02*
X32374Y231721D01*
G01X14002Y204272D02*
Y213349D01*
G01X15857Y202417D02*
X14002Y204272D01*
G01X13989Y199411D02*
X12200Y201200D01*
G01X24593Y199411D02*
X13989D01*
G01X25645Y198359D02*
X24593Y199411D01*
G01X25645Y194959D02*
Y198359D01*
G01X24966Y194280D02*
X25645Y194959D01*
G01X21010Y194280D02*
X24966D01*
G01X10650Y202750D02*
X12200Y201200D01*
G01X7200Y202750D02*
X10650D01*
G01X13667Y154767D02*
X16598D01*
G01X12014Y153114D02*
X13667Y154767D01*
G01X50912Y152712D02*
X47933Y149733D01*
G01X50912Y154167D02*
Y152712D01*
G01X9050Y195250D02*
X13646D01*
G01X18340Y196840D02*
X21010D01*
G01X16750Y195250D02*
X18340Y196840D01*
G01X13646Y195250D02*
X16750D01*
G01X44750Y191610D02*
Y195610D01*
G01X40760Y194280D02*
X37190D01*
G01X42090Y195610D02*
X40760Y194280D01*
G01X44750Y195610D02*
X42090D01*
G01X16538Y180035D02*
Y173177D01*
G01X16253Y180320D02*
X16538Y180035D01*
G01X39422Y189160D02*
X37190D01*
G01X41420Y187162D02*
X39422Y189160D01*
G01X41420Y183780D02*
Y187162D01*
G01X44471Y180729D02*
X41420Y183780D01*
G01X46604Y180729D02*
X44471D01*
G01X47699Y179634D02*
X46604Y180729D01*
G01X48300Y175550D02*
X52400D01*
G01X48300Y179033D02*
X47699Y179634D01*
G01X48300Y175550D02*
Y179033D01*
G01X28346Y232283D02*
Y231477D01*
G01X38266Y288650D02*
X56061Y270855D01*
G01X15300Y288650D02*
X38266D01*
G01X15300Y297400D02*
X9238Y303462D01*
G01X15300Y288650D02*
Y297400D01*
G01X22960Y234771D02*
Y229875D01*
G01X28346Y240157D02*
X22960Y234771D01*
G01X25159Y291325D02*
X12598Y303886D01*
G01X39375Y291325D02*
X25159D01*
G01X58736Y271964D02*
X39375Y291325D01*
G01X34252Y236220D02*
X38189D01*
G01X32374Y234342D02*
X34252Y236220D01*
G01X32374Y231721D02*
Y234342D01*
G01X55800Y289900D02*
Y292900D01*
G01X54422Y288522D02*
X55800Y289900D01*
G01X50272Y288522D02*
X54422D01*
G01X55800Y309160D02*
Y292900D01*
G01X42126Y323674D02*
Y322835D01*
G01X34900Y330900D02*
X42126Y323674D01*
G01X19400Y330900D02*
X34900D01*
G01X9238Y320738D02*
X19400Y330900D01*
G01X9238Y303462D02*
Y320738D01*
G01X12598Y303886D02*
Y312992D01*
G01X51968D02*
X55800Y309160D01*
G01X88414Y70631D02*
Y91043D01*
G01X88413Y70630D02*
X88414Y70631D01*
G01X88413Y66196D02*
Y70630D01*
G01X90300Y64309D02*
X88413Y66196D01*
G01X90300Y55256D02*
Y64309D01*
G01X88712Y53668D02*
X90300Y55256D01*
G01X88712Y18832D02*
Y53668D01*
G01X92800Y14744D02*
X88712Y18832D01*
G01X92800Y11008D02*
Y14744D01*
G01X93189Y10619D02*
X92800Y11008D01*
G01X93189Y6299D02*
Y10619D01*
G01X102150Y28450D02*
X104300D01*
G01X99400Y25700D02*
X102150Y28450D01*
G01X99300Y25700D02*
X99400D01*
G01X106048Y32036D02*
Y35685D01*
G01X104300Y30288D02*
X106048Y32036D01*
G01X104300Y28450D02*
Y30288D01*
G01X116850Y36650D02*
Y34100D01*
G01X118800Y38600D02*
X116850Y36650D01*
G01X122815Y38600D02*
X118800D01*
G01X123830Y37585D02*
X122815Y38600D01*
G01X123830Y34391D02*
Y37585D01*
G01X116550Y33800D02*
X116850Y34100D01*
G01X116550Y27400D02*
Y33800D01*
G01Y23500D02*
Y27400D01*
G01X121700Y48900D02*
Y50300D01*
G01X123830Y46770D02*
X121700Y48900D01*
G01X123830Y43591D02*
Y46770D01*
G01X122250Y50850D02*
X121700Y50300D01*
G01X122250Y54000D02*
Y50850D01*
G01X139114Y24942D02*
Y89314D01*
G01X134834Y20662D02*
X139114Y24942D01*
G01X127084Y20662D02*
X134834D01*
G01X120938Y14516D02*
X127084Y20662D01*
G01X120938Y13963D02*
Y14516D01*
G01X118839Y11864D02*
X120938Y13963D01*
G01X118839Y6299D02*
Y11864D01*
G01X125800Y31200D02*
X129200Y27800D01*
G01X125800Y34391D02*
Y31200D01*
G01X129950Y27050D02*
X129200Y27800D01*
G01X129950Y24000D02*
Y27050D01*
G01X123839Y12755D02*
Y6299D01*
G01X126742Y15658D02*
X123839Y12755D01*
G01X85739Y71740D02*
Y89934D01*
G01X85738Y71739D02*
X85739Y71740D01*
G01X85738Y65087D02*
Y71739D01*
G01X87500Y63325D02*
X85738Y65087D01*
G01X87500Y56240D02*
Y63325D01*
G01X86036Y54776D02*
X87500Y56240D01*
G01X86036Y52560D02*
Y54776D01*
G01X86037Y52559D02*
X86036Y52560D01*
G01X86037Y17723D02*
Y52559D01*
G01X90040Y13720D02*
X86037Y17723D01*
G01X90040Y6299D02*
Y13720D01*
G01X121860Y31340D02*
Y34391D01*
G01X125700Y27500D02*
X121860Y31340D01*
G01X125700Y26500D02*
Y27500D01*
G01X136439Y46461D02*
X136400Y46500D01*
G01X136439Y31761D02*
Y46461D01*
G01X128950Y47050D02*
X132600D01*
G01X127770Y45870D02*
X128950Y47050D01*
G01X127770Y43591D02*
Y45870D01*
G01X135850Y47050D02*
X136400Y46500D01*
G01X132600Y47050D02*
X135850D01*
G01X80900Y60800D02*
X78600Y58500D01*
G01X82200Y60800D02*
X80900D01*
G01X78600Y56650D02*
Y58500D01*
G01X80600Y54650D02*
X78600Y56650D01*
G01X111958Y47358D02*
Y44885D01*
G01X115300Y50700D02*
X111958Y47358D01*
G01X115300Y53300D02*
Y50700D01*
G01X113300Y55300D02*
X115300Y53300D01*
G01X101100Y55300D02*
X113300D01*
G01X100100Y56300D02*
X101100Y55300D01*
G01X112600Y30200D02*
Y28700D01*
G01X109988Y32812D02*
X112600Y30200D01*
G01X109988Y35685D02*
Y32812D01*
G01X112600Y25850D02*
Y28700D01*
G01X111650Y24900D02*
X112600Y25850D01*
G01X125800Y50000D02*
X126100Y50300D01*
G01X125800Y43591D02*
Y50000D01*
G01X126100Y53650D02*
X125750Y54000D01*
G01X126100Y50300D02*
Y53650D01*
G01X93764Y68413D02*
Y93261D01*
G01X95800Y66377D02*
X93764Y68413D01*
G01X95800Y53188D02*
Y66377D01*
G01X94062Y51450D02*
X95800Y53188D01*
G01X94062Y27122D02*
Y51450D01*
G01X102638Y18546D02*
X94062Y27122D01*
G01X102638Y6299D02*
Y18546D01*
G01X101051Y36351D02*
X101200Y36500D01*
G01X101051Y32537D02*
Y36351D01*
G01X101201Y36501D02*
X101200Y36500D01*
G01X101222Y36501D02*
X101201D01*
G01X102033Y37312D02*
X101222Y36501D01*
G01X102284Y37312D02*
X102033D01*
G01X104572Y39600D02*
X102284Y37312D01*
G01X106500Y39600D02*
X104572D01*
G01X108018Y41118D02*
X106500Y39600D01*
G01X108018Y44885D02*
Y41118D01*
G01X86890Y13086D02*
Y6299D01*
G01X83362Y16614D02*
X86890Y13086D01*
G01X83362Y51450D02*
Y16614D01*
G01X83361Y51451D02*
X83362Y51450D01*
G01X83361Y55885D02*
Y51451D01*
G01X83362Y55886D02*
X83361Y55885D01*
G01X83362Y56467D02*
Y55886D01*
G01X84750Y57855D02*
X83362Y56467D01*
G01X84750Y62033D02*
Y57855D01*
G01X83063Y63720D02*
X84750Y62033D01*
G01X83063Y72848D02*
Y63720D01*
G01X83819Y11681D02*
Y6299D01*
G01X80000Y15500D02*
X83819Y11681D01*
G01X76900Y15500D02*
X80000D01*
G01X91089Y69522D02*
Y92152D01*
G01X91088Y69521D02*
X91089Y69522D01*
G01X91088Y67305D02*
Y69521D01*
G01X93100Y65293D02*
X91088Y67305D01*
G01X93100Y54272D02*
Y65293D01*
G01X91387Y52559D02*
X93100Y54272D01*
G01X91387Y26013D02*
Y52559D01*
G01X99489Y17911D02*
X91387Y26013D01*
G01X99489Y6299D02*
Y17911D01*
G01X108150Y28550D02*
X108300Y28700D01*
G01X108150Y24900D02*
Y28550D01*
G01X108300Y30818D02*
Y28700D01*
G01X108018Y31100D02*
X108300Y30818D01*
G01X108018Y35685D02*
Y31100D01*
G01X145883Y84219D02*
Y54000D01*
G01Y19983D02*
Y54000D01*
G01X143839Y17939D02*
X145883Y19983D01*
G01X143839Y6299D02*
Y17939D01*
G01X98196Y51800D02*
X101800D01*
G01X98071Y51675D02*
X98196Y51800D01*
G01X106300Y51550D02*
X106050Y51800D01*
G01X106300Y50500D02*
Y51550D01*
G01X107500Y49300D02*
X106300Y50500D01*
G01X108800Y49300D02*
X107500D01*
G01X109988Y48112D02*
X108800Y49300D01*
G01X109988Y44885D02*
Y48112D01*
G01X106050Y51800D02*
X101800D01*
G01X80600Y51150D02*
X76500D01*
G01X73800Y48850D02*
Y50900D01*
G01X75650Y47000D02*
X73800Y48850D01*
G01X75812Y47162D02*
X75650Y47000D01*
G01X75812Y48384D02*
Y47162D01*
G01X76500Y49072D02*
X75812Y48384D01*
G01X76500Y51150D02*
Y49072D01*
G01X73520Y68300D02*
X75100D01*
G01X73200Y67980D02*
X73520Y68300D01*
G01X75621D02*
X75100D01*
G01X77871Y66050D02*
X75621Y68300D01*
G01X79200Y66050D02*
X77871D01*
G01X79200Y70050D02*
Y66050D01*
G01X142700Y20900D02*
Y86300D01*
G01X137100Y15300D02*
X142700Y20900D01*
G01X137100Y15000D02*
Y15300D01*
G01X133839Y11739D02*
X137100Y15000D01*
G01X133839Y6299D02*
Y11739D01*
G01X88414Y91043D02*
X73857Y105600D01*
G01X75604Y74104D02*
Y76400D01*
G01Y80319D02*
Y76400D01*
G01X79604Y80319D02*
X75604D01*
G01X139114Y89314D02*
X158600Y108800D01*
G01X85739Y89934D02*
X73673Y102000D01*
G01X93762Y93263D02*
Y95627D01*
G01X93764Y93261D02*
X93762Y93263D01*
G01X83064Y72849D02*
X83063Y72848D01*
G01X83064Y88825D02*
Y72849D01*
G01X73085Y98804D02*
X83064Y88825D01*
G01X163289Y101625D02*
X145883Y84219D01*
G01X142700Y86300D02*
X161400Y105000D01*
G01X205500Y55700D02*
X205700Y55900D01*
G01X205500Y52250D02*
Y55700D01*
G01X206100Y56300D02*
X205700Y55900D01*
G01X206100Y64000D02*
Y56300D01*
G01X203560Y66540D02*
X206100Y64000D01*
G01X198400Y66540D02*
X203560D01*
G01X211000Y56100D02*
X211300D01*
G01X208900Y58200D02*
X211000Y56100D01*
G01X208900Y59000D02*
Y58200D01*
G01X214750Y56100D02*
X211300D01*
G01X215300Y56650D02*
X214750Y56100D01*
G01X204340Y71660D02*
X198400D01*
G01X220600Y59600D02*
Y61420D01*
G01X219500Y58500D02*
X220600Y59600D01*
G01X219500Y56650D02*
Y58500D01*
G01X201500Y57000D02*
X201600Y57100D01*
G01X201500Y52250D02*
Y57000D01*
G01X202364Y57864D02*
X201600Y57100D01*
G01X202364Y62736D02*
Y57864D01*
G01X201120Y63980D02*
X202364Y62736D01*
G01X198400Y63980D02*
X201120D01*
G01X148558Y13142D02*
Y43046D01*
G01X148839Y12861D02*
X148558Y13142D01*
G01X148839Y6299D02*
Y12861D01*
G01X148558Y52891D02*
Y43046D01*
G01X148661Y52994D02*
X148558Y52891D01*
G01X148661Y61192D02*
Y52994D01*
G01X148574Y61279D02*
X148661Y61192D01*
G01X148574Y77949D02*
Y61279D01*
G01X180750Y74250D02*
Y70200D01*
G01X184486Y53514D02*
X183300Y54700D01*
G01X185786Y53514D02*
X184486D01*
G01X193900Y45400D02*
X185786Y53514D01*
G01X202150Y45400D02*
X193900D01*
G01X205500Y48750D02*
X202150Y45400D01*
G01X182237Y55763D02*
X183300Y54700D01*
G01X182237Y66484D02*
Y55763D01*
G01X180750Y67971D02*
X182237Y66484D01*
G01X180750Y70200D02*
Y67971D01*
G01X151336Y41428D02*
Y62300D01*
G01X151249Y41341D02*
X151336Y41428D01*
G01X151249Y31760D02*
Y41341D01*
G01X151336Y31673D02*
X151249Y31760D01*
G01X151336Y15164D02*
Y31673D01*
G01X153839Y12661D02*
X151336Y15164D01*
G01X153839Y6299D02*
Y12661D01*
G01X151249Y62388D02*
Y76840D01*
G01X151336Y62301D02*
X151249Y62388D01*
G01X151336Y62300D02*
Y62301D01*
G01X197500Y48750D02*
X201500D01*
G01X184750Y68100D02*
Y70200D01*
G01X184912Y67938D02*
X184750Y68100D01*
G01X184912Y58288D02*
Y67938D01*
G01X194450Y48750D02*
X184912Y58288D01*
G01X197500Y48750D02*
X194450D01*
G01X184750Y70200D02*
X187400Y72850D01*
G01X170850Y54340D02*
Y48800D01*
G01X170750Y54440D02*
X170850Y54340D01*
G01X164942Y40642D02*
X163452D01*
G01X170700Y46400D02*
X164942Y40642D01*
G01X170700Y48650D02*
Y46400D01*
G01X170850Y48800D02*
X170700Y48650D01*
G01X159058Y40642D02*
X163452D01*
G01X157686Y42014D02*
X159058Y40642D01*
G01X157686Y64933D02*
Y42014D01*
G01X157599Y65020D02*
X157686Y64933D01*
G01X157599Y74460D02*
Y65020D01*
G01X192366Y60566D02*
Y61922D01*
G01X190846Y59046D02*
X192366Y60566D01*
G01X188250Y59046D02*
X190846D01*
G01X193576Y66750D02*
X192500D01*
G01X195926Y69100D02*
X193576Y66750D01*
G01X198400Y69100D02*
X195926D01*
G01X192366Y66616D02*
Y61922D01*
G01X192500Y66750D02*
X192366Y66616D01*
G01X169437Y71358D02*
Y70136D01*
G01X171553Y73474D02*
X169437Y71358D01*
G01X167904Y70136D02*
X162610Y75430D01*
G01X169437Y70136D02*
X167904D01*
G01X220750Y42250D02*
X222500D01*
G01X220000Y43000D02*
X220750Y42250D01*
G01X217832Y43000D02*
X220000D01*
G01X217732Y42900D02*
X217832Y43000D01*
G01X217732Y39818D02*
Y42900D01*
G01X218300Y39250D02*
X217732Y39818D01*
G01X222925Y63980D02*
X220600D01*
G01X224547Y62358D02*
X222925Y63980D01*
G01X222500Y42250D02*
X223787Y43537D01*
G01X212290Y44990D02*
X214033D01*
G01X209735Y42435D02*
X212290Y44990D01*
G01X207150Y42435D02*
X209735D01*
G01X207015Y42300D02*
X207150Y42435D01*
G01X203691Y42300D02*
X207015D01*
G01X202300Y40909D02*
X203691Y42300D01*
G01X202300Y35564D02*
Y40909D01*
G01X203299Y34565D02*
X202300Y35564D01*
G01X207150Y34565D02*
X203299D01*
G01X214390Y44990D02*
X214033D01*
G01X217232Y47832D02*
X214390Y44990D01*
G01X217232Y49139D02*
Y47832D01*
G01X214050Y53150D02*
X215300D01*
G01X213162Y52262D02*
X214050Y53150D01*
G01X209522Y52262D02*
X213162D01*
G01X217232Y51868D02*
Y49139D01*
G01X215950Y53150D02*
X217232Y51868D01*
G01X215300Y53150D02*
X215950D01*
G01X226448Y33705D02*
X223378Y30635D01*
G01X220600Y66540D02*
X224760D01*
G01X215378Y29355D02*
X219378D01*
G01X222098D02*
X223378Y30635D01*
G01X219378Y29355D02*
X222098D01*
G01X163734Y108800D02*
X165206Y110272D01*
G01X158600Y108800D02*
X163734D01*
G01X169000Y114066D02*
X165206Y110272D01*
G01X169000Y130700D02*
Y114066D01*
G01X172400Y134100D02*
X169000Y130700D01*
G01X172400Y170800D02*
Y134100D01*
G01X198470Y115244D02*
Y113600D01*
G01X200165Y116939D02*
X198470Y115244D01*
G01X203352Y116939D02*
X200165D01*
G01X204861Y115430D02*
X203352Y116939D01*
G01X207534Y115430D02*
X204861D01*
G01X193500Y135835D02*
X215516D01*
G01X208170Y146653D02*
X212717Y151200D01*
G01X176870Y146653D02*
X208170D01*
G01X190900Y114700D02*
X191900Y115700D01*
G01X190900Y112200D02*
Y114700D01*
G01X215600Y146580D02*
Y151200D01*
G01X215520Y146500D02*
X215600Y146580D01*
G01X218100Y143920D02*
X215520Y146500D01*
G01X218100Y138100D02*
Y143920D01*
G01X215835Y135835D02*
X218100Y138100D01*
G01X215516Y135835D02*
X215835D01*
G01X194700Y115700D02*
X191900D01*
G01X196800Y113600D02*
X194700Y115700D01*
G01X198470Y113600D02*
X196800D01*
G01X192670Y89580D02*
X192250Y90000D01*
G01X198400Y89580D02*
X192670D01*
G01X180180Y92100D02*
X182800D01*
G01X178680Y93600D02*
X180180Y92100D01*
G01X172026Y93600D02*
X178680D01*
G01X171263Y92837D02*
X172026Y93600D01*
G01X200900Y105500D02*
X203050D01*
G01X200100Y106300D02*
X200900Y105500D01*
G01X195570Y106300D02*
X200100D01*
G01X195569Y106301D02*
X195570Y106300D01*
G01X186699Y106301D02*
X195569D01*
G01X186698Y106300D02*
X186699Y106301D01*
G01X184900Y106300D02*
X186698D01*
G01X186128Y92100D02*
X182800D01*
G01X186953Y92925D02*
X186128Y92100D01*
G01X190025Y92925D02*
X186953D01*
G01X192250Y90700D02*
X190025Y92925D01*
G01X192250Y90000D02*
Y90700D01*
G01X216909Y124809D02*
X215000Y122900D01*
G01X218832Y124809D02*
X216909D01*
G01X214100Y119000D02*
X214850D01*
G01X212500Y117400D02*
X214100Y119000D01*
G01X209976Y117400D02*
X212500D01*
G01X214850Y122750D02*
X215000Y122900D01*
G01X214850Y119000D02*
Y122750D01*
G01X148661Y78036D02*
X148574Y77949D01*
G01X148661Y83213D02*
Y78036D01*
G01X164398Y98950D02*
X148661Y83213D01*
G01X180898Y98950D02*
X164398D01*
G01X181573Y98275D02*
X180898Y98950D01*
G01X190025Y98275D02*
X181573D01*
G01X190026Y98276D02*
X190025Y98275D01*
G01X192242Y98276D02*
X190026D01*
G01X195588Y94930D02*
X192242Y98276D01*
G01X211630Y94930D02*
X195588D01*
G01X213900Y97200D02*
X211630Y94930D01*
G01X220700Y97200D02*
X213900D01*
G01X226275Y102775D02*
X220700Y97200D01*
G01X184720Y78220D02*
X180750Y74250D01*
G01X187400Y78220D02*
X184720D01*
G01X182007Y101625D02*
X163289D01*
G01X182682Y100950D02*
X182007Y101625D01*
G01X188916Y100950D02*
X182682D01*
G01X188917Y100951D02*
X188916Y100950D01*
G01X193351Y100951D02*
X188917D01*
G01X196697Y97605D02*
X193351Y100951D01*
G01X209605Y97605D02*
X196697D01*
G01X211900Y99900D02*
X209605Y97605D01*
G01X219600Y99900D02*
X211900D01*
G01X223600Y103900D02*
X219600Y99900D01*
G01X223600Y152029D02*
Y103900D01*
G01X222500Y94500D02*
X228950Y100950D01*
G01X215400Y94500D02*
X222500D01*
G01X213155Y92255D02*
X215400Y94500D01*
G01X194479Y92255D02*
X213155D01*
G01X191134Y95600D02*
X194479Y92255D01*
G01X180464Y95600D02*
X191134D01*
G01X179789Y96275D02*
X180464Y95600D01*
G01X165507Y96275D02*
X179789D01*
G01X151336Y82104D02*
X165507Y96275D01*
G01X151336Y76927D02*
Y82104D01*
G01X151249Y76840D02*
X151336Y76927D01*
G01X187400Y72850D02*
Y75660D01*
G01X161400Y105000D02*
X171900D01*
G01X182566Y104850D02*
X180800D01*
G01X183791Y103625D02*
X182566Y104850D01*
G01X187807Y103625D02*
X183791D01*
G01X187808Y103626D02*
X187807Y103625D01*
G01X194460Y103626D02*
X187808D01*
G01X197806Y100280D02*
X194460Y103626D01*
G01X207790Y100280D02*
X197806D01*
G01X209550Y102040D02*
X207790Y100280D01*
G01X209550Y102940D02*
Y102040D01*
G01X172050Y104850D02*
X171900Y105000D01*
G01X180800Y104850D02*
X172050D01*
G01X160794Y86348D02*
Y86162D01*
G01X164837Y90391D02*
X160794Y86348D01*
G01X176877Y90391D02*
X164837D01*
G01X177843Y89425D02*
X176877Y90391D01*
G01X179575Y89425D02*
X177843D01*
G01X180600Y88400D02*
X179575Y89425D01*
G01X180600Y85978D02*
Y88400D01*
G01X183238Y83340D02*
X180600Y85978D01*
G01X187400Y83340D02*
X183238D01*
G01X154011Y78048D02*
X157599Y74460D01*
G01X154011Y80995D02*
Y78048D01*
G01X158553Y85537D02*
X154011Y80995D01*
G01X159983Y85537D02*
X158553D01*
G01X160608Y86162D02*
X159983Y85537D01*
G01X160794Y86162D02*
X160608D01*
G01X173474Y73474D02*
X171553D01*
G01X174600Y74600D02*
X173474Y73474D01*
G01X174600Y75660D02*
Y74600D01*
G01X160888Y77152D02*
X162610Y75430D01*
G01X159117Y77152D02*
X160888D01*
G01X156891Y79378D02*
X159117Y77152D01*
G01X169973Y77000D02*
X168936Y75963D01*
G01X171055Y77000D02*
X169973D01*
G01X172275Y78220D02*
X171055Y77000D01*
G01X174600Y78220D02*
X172275D01*
G01X164700Y77124D02*
Y82300D01*
G01X165861Y75963D02*
X164700Y77124D01*
G01X168936Y75963D02*
X165861D01*
G01X164491Y82091D02*
X164700Y82300D01*
G01X159711Y82091D02*
X164491D01*
G01X183166Y108350D02*
X180800D01*
G01X184016Y109200D02*
X183166Y108350D01*
G01X199860Y109200D02*
X184016D01*
G01X201000Y108060D02*
X199860Y109200D01*
G01X203050Y108060D02*
X201000D01*
G01X184200Y121500D02*
X192721D01*
G01X180800Y118100D02*
X184200Y121500D01*
G01X180800Y114300D02*
Y118100D01*
G01X206504Y120400D02*
X207534Y119370D01*
G01X199842Y120400D02*
X206504D01*
G01X197817Y118375D02*
X199842Y120400D01*
G01X194625Y118375D02*
X197817D01*
G01X192882Y120118D02*
X194625Y118375D01*
G01X192882Y121339D02*
Y120118D01*
G01X192721Y121500D02*
X192882Y121339D01*
G01X180800Y108350D02*
Y114300D01*
G01X179700Y178100D02*
X172400Y170800D01*
G01X188711Y178100D02*
X179700D01*
G01X193583Y173228D02*
X188711Y178100D01*
G01X207590Y186610D02*
X211900Y182300D01*
G01X207590Y188260D02*
Y186610D01*
G01X212900Y181300D02*
X215650D01*
G01X211900Y182300D02*
X212900Y181300D01*
G01X215650D02*
Y185300D01*
G01X199900Y171945D02*
X206763Y165082D01*
G01X199900Y175400D02*
Y171945D01*
G01X192100Y183200D02*
X199900Y175400D01*
G01X186229Y183200D02*
X192100D01*
G01X180911Y188518D02*
X186229Y183200D01*
G01X180911Y193573D02*
Y188518D01*
G01X186138Y198800D02*
X180911Y193573D01*
G01X201579Y198800D02*
X186138D01*
G01X211012Y208233D02*
X201579Y198800D01*
G01X211012Y209533D02*
Y208233D01*
G01X214917Y213438D02*
X211012Y209533D01*
G01X221923Y213438D02*
X214917D01*
G01X225998Y217513D02*
X221923Y213438D01*
G01X220200Y151645D02*
Y151000D01*
G01X206763Y165082D02*
X220200Y151645D01*
G01X212717Y151200D02*
X215600D01*
G01X187880Y190820D02*
X191410D01*
G01X187642Y191058D02*
X187880Y190820D01*
G01X183653Y191058D02*
X187642D01*
G01X216000Y190500D02*
X216100Y190400D01*
G01X211100Y190500D02*
X216000D01*
G01X210780Y190820D02*
X211100Y190500D01*
G01X207590Y190820D02*
X210780D01*
G01X219700Y190400D02*
X216100D01*
G01X222150Y192850D02*
X219700Y190400D01*
G01X223200Y192850D02*
X222150D01*
G01X223200Y188800D02*
Y192850D01*
G01X209900Y169513D02*
X226275Y153138D01*
G01X209900Y172650D02*
Y169513D01*
G01X178695Y185627D02*
Y185153D01*
G01X171521Y192801D02*
X178695Y185627D01*
G01X171521Y227281D02*
Y192801D01*
G01X209900Y179800D02*
X207400Y182300D01*
G01X209900Y176150D02*
Y179800D01*
G01X200400Y189300D02*
X207400Y182300D01*
G01X200400Y192600D02*
Y189300D01*
G01X197060Y195940D02*
X200400Y192600D01*
G01X191410Y195940D02*
X197060D01*
G01X205500Y170129D02*
X223600Y152029D01*
G01X205500Y172650D02*
Y170129D01*
G01Y178500D02*
X201900Y182100D01*
G01X205500Y176150D02*
Y178500D01*
G01X196400Y187600D02*
X201900Y182100D01*
G01X196400Y191000D02*
Y187600D01*
G01X194020Y193380D02*
X196400Y191000D01*
G01X191410Y193380D02*
X194020D01*
G01X178563Y197265D02*
Y197014D01*
G01X174196Y201632D02*
X178563Y197265D01*
G01X174196Y226172D02*
Y201632D01*
G01X218534Y204666D02*
Y202560D01*
G01X217850Y205350D02*
X218534Y204666D01*
G01X217850Y206700D02*
Y205350D01*
G01X215650Y197650D02*
Y197300D01*
G01X218534Y200534D02*
X215650Y197650D01*
G01X218534Y202560D02*
Y200534D01*
G01X212345Y193380D02*
X207590D01*
G01X215650Y196685D02*
X212345Y193380D01*
G01X215650Y197300D02*
Y196685D01*
G01X213852Y222345D02*
Y221230D01*
G01X212181Y224016D02*
X213852Y222345D01*
G01X184700Y156500D02*
X181800Y159400D01*
G01X188583Y156500D02*
X184700D01*
G01X180000Y161200D02*
X181800Y159400D01*
G01X180000Y169645D02*
Y161200D01*
G01X183583Y173228D02*
X180000Y169645D01*
G01X205463Y295742D02*
X225998Y275207D01*
G01X181758Y295742D02*
X205463D01*
G01X172835Y304665D02*
X181758Y295742D01*
G01X184397Y240157D02*
X171521Y227281D01*
G01X188583Y240157D02*
X184397D01*
G01X180307Y232283D02*
X174196Y226172D01*
G01X188583Y232283D02*
X180307D01*
G01X220723Y296373D02*
X220891Y296541D01*
G01X220723Y291395D02*
Y296373D01*
G01X220891Y300690D02*
Y296541D01*
G01X207750Y224016D02*
X212181D01*
G01X213852Y228168D02*
Y226930D01*
G01X212030Y229990D02*
X213852Y228168D01*
G01X209506Y229990D02*
X212030D01*
G01X172835Y312992D02*
Y304665D01*
G01X212205Y309376D02*
X220891Y300690D01*
G01X212205Y312992D02*
Y309376D01*
G01X225100Y316231D02*
X222189D01*
G01X218369D02*
X222189D01*
G01X211765Y322835D02*
X218369Y316231D01*
G01X202363Y322835D02*
X211765D01*
G01X224547Y45132D02*
Y62358D01*
G01X223787Y44372D02*
X224547Y45132D01*
G01X223787Y43537D02*
Y44372D01*
G01X226448Y34016D02*
Y33705D01*
G01X226462Y34030D02*
X226448Y34016D01*
G01X226462Y43162D02*
Y34030D01*
G01X227300Y44000D02*
X226462Y43162D01*
G01X227300Y64000D02*
Y44000D01*
G01X224760Y66540D02*
X227300Y64000D01*
G01X226275Y153138D02*
Y102775D01*
G01X228950Y100950D02*
Y312381D01*
G01X225998Y275207D02*
Y217513D01*
G01X228950Y312381D02*
X225100Y316231D01*
M02*
